FILE_TYPE = MULTI_PHYS_TABLE;

PART 'Q_LED'

{========================================================================================}
:COLOR                      | PACK_TYPE | MANUF_PN                    | MATERIAL | PART_NUMBER    = STANDARD        | LIFECYCLE          | PART_NUMBER   | JEDEC_TYPE                     | CLASS | DESCRIPTION                                                           | COMPONENT_TYPE | LEAD_LENGTH | LPID | DAY        ;
{========================================================================================}
 'GREEN'                    | 'THLF'    | 'L-710A8CB/1ZGT'            | 'IC'     | 'BEGR0175D00'(!) = 'End of Design' | 'Comp-Approve'     | 'BEGR0175D00' |'LED_5514207XA'| 'IC'  | 'LED DIP(2P) GREEN(L-710A8CB/1ZGT)'                                   | ''             | ''          | ''   | ''        
 'GREEN'                    | 'THLF'    | 'L-710A8CB/1ZGT'            | 'EMPTY'  | 'BEGR0175D00'(!) = 'End of Design' | 'Comp-Approve'     | 'BEGR0175D00' |'LED_5514207XA'| 'IO'  | 'LED DIP(2P) GREEN(L-710A8CB/1ZGT)'                                   | ''             | ''          | ''   | ''        
 'YELLOW'                   | 'THLF'    | 'L-710A8EW/1YD'             | 'IC'     | 'BEYL0052D00'(!) = 'End of Design' | 'Comp-Approve'     | 'BEYL0052D00' |'LED_710A8EW'| 'IC'  | 'LED DIP(2P) YELLOW(L-710A8EW/1YD)'                                   | ''             | ''          | ''   | ''        
 'YELLOW'                   | 'THLF'    | 'L-710A8EW/1YD'             | 'EMPTY'  | 'BEYL0052D00'(!) = 'End of Design' | 'Comp-Approve'     | 'BEYL0052D00' |'LED_710A8EW'| 'IO'  | 'LED DIP(2P) YELLOW(L-710A8EW/1YD)'                                   | ''             | ''          | ''   | ''        
 'GREEN'                    | 'SMLF'    | 'KPHM-1608SGC-T'            | 'IC'     | 'BEGR0203Z00'(!) = 'End of Design' | 'Comp-Approve'     | 'BEGR0203Z00' |'LED_19217'| 'IC'  | 'LED SMD(2P) BRIGHT GREEN KPHM-1608SGC-T'                             | ''             | ''          | ''   | ''        
 'GREEN'                    | 'SMLF'    | 'KPHM-1608SGC-T'            | 'EMPTY'  | 'BEGR0203Z00'(!) = 'End of Design' | 'Comp-Approve'     | 'BEGR0203Z00' |'LED_19217'| 'IO'  | 'LED SMD(2P) BRIGHT GREEN KPHM-1608SGC-T'                             | ''             | ''          | ''   | ''        
 'YELLOW'                   | 'SMLF'    | 'KPHM-1608YC-T'             | 'IC'     | 'BEYL0071Z01'(!) = 'End of Design' | 'Comp-Approve'     | 'BEYL0071Z01' |'LED_19217'| 'IC'  | 'LED SMD(2P) YELLOW KPHM-1608YC-T'                                    | ''             | ''          | ''   | ''        
 'YELLOW'                   | 'SMLF'    | 'KPHM-1608YC-T'             | 'EMPTY'  | 'BEYL0071Z01'(!) = 'End of Design' | 'Comp-Approve'     | 'BEYL0071Z01' |'LED_19217'| 'IO'  | 'LED SMD(2P) YELLOW KPHM-1608YC-T'                                    | ''             | ''          | ''   | ''        
 'BLUE'                     | 'SMLF'    | 'KPHM-1608QBC-C'            | 'IC'     | 'BEBL0101Z00'(!) = 'End of Design' | 'Comp-Approve'     | 'BEBL0101Z00' |'LED_19217'| 'IC'  | 'LED SMD(2P) BLUE KPHM-1608QBC-C'                                     | ''             | ''          | ''   | ''        
 'BLUE'                     | 'SMLF'    | 'KPHM-1608QBC-C'            | 'EMPTY'  | 'BEBL0101Z00'(!) = 'End of Design' | 'Comp-Approve'     | 'BEBL0101Z00' |'LED_19217'| 'IO'  | 'LED SMD(2P) BLUE KPHM-1608QBC-C'                                     | ''             | ''          | ''   | ''        
 'RED'                      | 'SMLF'    | 'KPHM-1608EC-T'             | 'IC'     | 'BERD0054Z00'(!) = 'End of Design' | 'Comp-Approve'     | 'BERD0054Z00' |'LED_19217'| 'IC'  | 'LED SMD(2P) RED KPHM-1608EC-T'                                       | ''             | ''          | ''   | ''        
 'RED'                      | 'SMLF'    | 'KPHM-1608EC-T'             | 'EMPTY'  | 'BERD0054Z00'(!) = 'End of Design' | 'Comp-Approve'     | 'BERD0054Z00' |'LED_19217'| 'IO'  | 'LED SMD(2P) RED KPHM-1608EC-T'                                       | ''             | ''          | ''   | ''        
 'LED YELLOW'               | 'SMLF'    | '19-21UYC/S530-A2/TR8 '     | 'IC'     | 'BEYL0016Z08'(!) = 'End of Design' | 'Comp-Approve'     | 'BEYL0016Z08' |'LED_1921'| 'IC'  | 'LED SMD(2P)YEL(19-21UYC/S530-A2/TR8)  '                              | ''             | ''          | ''   | '20100709'
 'LED YELLOW'               | 'SMLF'    | '19-21UYC/S530-A2/TR8 '     | 'EMPTY'  | 'BEYL0016Z08'(!) = 'End of Design' | 'Comp-Approve'     | 'BEYL0016Z08' |'LED_1921'| 'IO'  | 'LED SMD(2P)YEL(19-21UYC/S530-A2/TR8)  '                              | ''             | ''          | ''   | '20100709'
 'GREEN'                    | 'SMLF'    | '19-21VGC/TR8'              | 'IC'     | 'BEGR0037Z04'(!) = 'End of Design' | 'End of Life'      | 'BEGR0037Z04' |'LED_1921_EOL'| 'IC'  | 'LED SMD 2P GREEN(1.6*0.8*0.8)VGC/TR8'                                | ''             | ''          | ''   | ''        
 'GREEN'                    | 'SMLF'    | '19-21VGC/TR8'              | 'EMPTY'  | 'BEGR0037Z04'(!) = 'End of Design' | 'End of Life'      | 'BEGR0037Z04' |'LED_1921_EOL'| 'IO'  | 'LED SMD 2P GREEN(1.6*0.8*0.8)VGC/TR8'                                | ''             | ''          | ''   | ''        
 'GREEN'                    | 'SMLF'    | 'KPHM-1608VGC-A'            | 'IC'     | 'BEGR0237Z00'(!) = 'End of Design' | 'Comp-Approve'     | 'BEGR0237Z00' |'LED_19217'| 'IC'  | 'LED SMD(2P) GREEN KPHM-1608VGC-A'                                    | ''             | ''          | ''   | ''        
 'GREEN'                    | 'SMLF'    | 'KPHM-1608VGC-A'            | 'EMPTY'  | 'BEGR0237Z00'(!) = 'End of Design' | 'Comp-Approve'     | 'BEGR0237Z00' |'LED_19217'| 'IO'  | 'LED SMD(2P) GREEN KPHM-1608VGC-A'                                    | ''             | ''          | ''   | ''        
 'BLUE'                     | 'THLF'    | 'L-1384AD/1PBD-A-DTS'       | 'IC'     | 'BEBL0104D01'(!) = 'End of Design' | 'Comp-Approve'     | 'BEBL0104D01' |'LED_L1384AD'| 'IC'  | 'LED DIP(2P)BLUE(L-1384AD/1PBD-A-DTS)'                                | ''             | ''          | ''   | ''        
 'BLUE'                     | 'THLF'    | 'L-1384AD/1PBD-A-DTS'       | 'EMPTY'  | 'BEBL0104D01'(!) = 'End of Design' | 'Comp-Approve'     | 'BEBL0104D01' |'LED_L1384AD'| 'IO'  | 'LED DIP(2P)BLUE(L-1384AD/1PBD-A-DTS)'                                | ''             | ''          | ''   | ''        
 'BLUE'                     | 'THLF'    | 'L-710A8EW/1QBD-C'          | 'IC'     | 'BEBL0150D00'(!) = 'End of Design' | 'Comp-Approve'     | 'BEBL0150D00' |'LED_710A8EW'| 'IC'  | 'LED DIP 2P BLUE (L-710A8EW/1QBD-C)'                                  | ''             | ''          | ''   | ''        
 'BLUE'                     | 'THLF'    | 'L-710A8EW/1QBD-C'          | 'EMPTY'  | 'BEBL0150D00'(!) = 'End of Design' | 'Comp-Approve'     | 'BEBL0150D00' |'LED_710A8EW'| 'IO'  | 'LED DIP 2P BLUE (L-710A8EW/1QBD-C)'                                  | ''             | ''          | ''   | ''        
 'LED YELLOW'               | 'SMLF'    | '15-21VYC/TR8(HT)     '     | 'IC'     | 'BEYL0008Z05'(!) = 'End of Design' | 'End of Life'      | 'BEYL0008Z05' |'LED_1521_ERROR_EOL'| 'IC'  | 'LED(2P,SMD) YELLOW 15-21VYC/TR8(HT)-Need new spec check-20170503   ' | ''             | ''          | ''   | '20100709'
 'LED YELLOW'               | 'SMLF'    | '15-21VYC/TR8(HT)     '     | 'EMPTY'  | 'BEYL0008Z05'(!) = 'End of Design' | 'End of Life'      | 'BEYL0008Z05' |'LED_1521_ERROR_EOL'| 'IO'  | 'LED(2P,SMD) YELLOW 15-21VYC/TR8(HT)-Need new spec check-20170503   ' | ''             | ''          | ''   | '20100709'
 'LED AMBER '               | 'SMLF'    | '19-21UYOC-S530-A3-TR8'     | 'IC'     | 'BEAB0014Z00'(!) = 'End of Design' | 'Comp-Approve'     | 'BEAB0014Z00' |'LED_1921XA'| 'IC'  | 'LED SMD(2P)AMBER(19-21UYOC/S530-A3-TR8)'                             | ''             | ''          | ''   | '20100709'
 'LED AMBER '               | 'SMLF'    | '19-21UYOC-S530-A3-TR8'     | 'EMPTY'  | 'BEAB0014Z00'(!) = 'End of Design' | 'Comp-Approve'     | 'BEAB0014Z00' |'LED_1921XA'| 'IO'  | 'LED SMD(2P)AMBER(19-21UYOC/S530-A3-TR8)'                             | ''             | ''          | ''   | '20100709'
 'LED RED   '               | 'SMLF'    | '19-21SURC-S530-A3-TR8'     | 'IC'     | 'BERD0035Z03'(!) = 'End of Design' | 'Comp-Approve'     | 'BERD0035Z03' |'LED_1921XA'| 'IC'  | 'LED SMD(2P) RED(19-21SURC-S530-A3-TR8)'                              | ''             | ''          | ''   | '20100709'
 'LED RED   '               | 'SMLF'    | '19-21SURC-S530-A3-TR8'     | 'EMPTY'  | 'BERD0035Z03'(!) = 'End of Design' | 'Comp-Approve'     | 'BERD0035Z03' |'LED_1921XA'| 'IO'  | 'LED SMD(2P) RED(19-21SURC-S530-A3-TR8)'                              | ''             | ''          | ''   | '20100709'
 'LED GREEN '               | 'SMLF'    | 'APT2012QGW-F01-INT   '     | 'IC'     | 'BEGR0102Z19'(!) = 'End of Design' | 'Comp-Approve'     | 'BEGR0102Z19' |'LED_APT2012'| 'IC'  | 'LED SMD(2P)GREEN APT2012QGW-F01-INT   '                              | ''             | ''          | ''   | '20100709'
 'LED GREEN '               | 'SMLF'    | 'APT2012QGW-F01-INT   '     | 'EMPTY'  | 'BEGR0102Z19'(!) = 'End of Design' | 'Comp-Approve'     | 'BEGR0102Z19' |'LED_APT2012'| 'IO'  | 'LED SMD(2P)GREEN APT2012QGW-F01-INT   '                              | ''             | ''          | ''   | '20100709'
 'LED GREEN '               | 'SMLF'    | 'APT2012NW-F01-INT '        | 'IC'     | 'BE0R0012Z17'(!) = 'End of Design' | 'Comp-Approve'     | 'BE0R0012Z17' |'LED_APT2012'| 'IC'  | 'LED SMD(2P)ORANGE APT2012NW-F01-INT'                                 | ''             | ''          | ''   | '20100709'
 'LED GREEN '               | 'SMLF'    | 'APT2012NW-F01-INT '        | 'EMPTY'  | 'BE0R0012Z17'(!) = 'End of Design' | 'Comp-Approve'     | 'BE0R0012Z17' |'LED_APT2012'| 'IO'  | 'LED SMD(2P)ORANGE APT2012NW-F01-INT'                                 | ''             | ''          | ''   | '20100709'
 'LED BLUE'                 | 'THLF'    | 'L-7104EW-1PBD-A-DTS'       | 'IC'     | 'BEBL0141D00'(!) = 'End of Design' | 'Comp-Approve'     | 'BEBL0141D00' |'LED_710A8EW'| 'IC'  | 'LED DIP(2P) BLUE L-7104EW-1PBD-A-DTS'                                | ''             | ''          | ''   | '20100915'
 'LED BLUE'                 | 'THLF'    | 'L-7104EW-1PBD-A-DTS'       | 'EMPTY'  | 'BEBL0141D00'(!) = 'End of Design' | 'Comp-Approve'     | 'BEBL0141D00' |'LED_710A8EW'| 'IO'  | 'LED DIP(2P) BLUE L-7104EW-1PBD-A-DTS'                                | ''             | ''          | ''   | '20100915'
 'LED_GREEN'                | 'THLF'    | 'L-7104EW/1GD'              | 'IC'     | 'BEGR0234D00'(!) = 'End of Design' | 'Comp-Approve'     | 'BEGR0234D00' |'LED_710A8EW'| 'IC'  | 'LED DIP(2P) GREEN L-7104EW/1GD'                                      | ''             | ''          | ''   | '20100915'
 'LED_GREEN'                | 'THLF'    | 'L-7104EW/1GD'              | 'EMPTY'  | 'BEGR0234D00'(!) = 'End of Design' | 'Comp-Approve'     | 'BEGR0234D00' |'LED_710A8EW'| 'IO'  | 'LED DIP(2P) GREEN L-7104EW/1GD'                                      | ''             | ''          | ''   | '20100915'
 'LED_YELLOW'               | 'SMLF'    | '19-213/Y2C-AP1Q1BZ/3T'     | 'IC'     | 'BEYL0107Z00'(!) = ''              | ''                 | 'BEYL0107Z00' |'LED_1921'| 'IC'  | 'LED SMD YELLOW (19-213/Y2C-AP1Q1BZ/3T)'                              | ''             | ''          | ''   | '20101125'
 'LED_YELLOW'               | 'SMLF'    | '19-213/Y2C-AP1Q1BZ/3T'     | 'EMPTY'  | 'BEYL0107Z00'(!) = ''              | ''                 | 'BEYL0107Z00' |'LED_1921'| 'IO'  | 'LED SMD YELLOW (19-213/Y2C-AP1Q1BZ/3T)'                              | ''             | ''          | ''   | '20101125'
 'LED_GREEN'                | 'SMLF'    | 'LTST-C171GKT-T'            | 'IC'     | 'BEGR0182Z00'(!) = ''              | ''                 | 'BEGR0182Z00' |'LED_C171GKT'| 'IC'  | 'LED SMD(2P) GREEN(LTST-C171GKT-T)'                                   | ''             | ''          | ''   | '20110223'
 'LED_GREEN'                | 'SMLF'    | 'LTST-C171GKT-T'            | 'EMPTY'  | 'BEGR0182Z00'(!) = ''              | ''                 | 'BEGR0182Z00' |'LED_C171GKT'| 'IO'  | 'LED SMD(2P) GREEN(LTST-C171GKT-T)'                                   | ''             | ''          | ''   | '20110223'
 'LED_ORANGE'               | 'SMLF'    | 'LTST-C170AKT'              | 'IC'     | 'BE0R0008Z01'(!) = ''              | ''                 | 'BE0R0008Z01' |'LED_170VY_H44'| 'IC'  | 'LED SMD 2P ORANGE (LTST-C170AKT)'                                    | ''             | ''          | ''   | '20110609'
 'LED_ORANGE'               | 'SMLF'    | 'LTST-C170AKT'              | 'EMPTY'  | 'BE0R0008Z01'(!) = ''              | ''                 | 'BE0R0008Z01' |'LED_170VY_H44'| 'IO'  | 'LED SMD 2P ORANGE (LTST-C170AKT)'                                    | ''             | ''          | ''   | '20110609'
 'LED YELLOW'               | 'SMLF'    | 'LTST-C190KSKT'             | 'IC'     | 'BEYL0024Z01'(!) = ''              | ''                 | 'BEYL0024Z01' |'LED_1921XA'| 'IC'  | 'LED SMD (2P) YELLOW(LTST-C190KSKT) 0603'                             | ''             | ''          | ''   | '20111207'
 'LED YELLOW'               | 'SMLF'    | 'LTST-C190KSKT'             | 'EMPTY'  | 'BEYL0024Z01'(!) = ''              | ''                 | 'BEYL0024Z01' |'LED_1921XA'| 'IO'  | 'LED SMD (2P) YELLOW(LTST-C190KSKT) 0603'                             | ''             | ''          | ''   | '20111207'
 'LED SMD BLUE'             | 'SMLF'    | '11-21/BHC-AP1Q2B2Z/2T'     | 'IC'     | 'BEBL0105Z00'(!) = ''              | ''                 | 'BEBL0105Z00' |'LED_1121'| 'IC'  | 'LED SMD BLUE(11-21/BHC-AP1Q2B2Z/2T)'                                 | ''             | ''          | ''   | '20111207'
 'LED SMD BLUE'             | 'SMLF'    | '11-21/BHC-AP1Q2B2Z/2T'     | 'EMPTY'  | 'BEBL0105Z00'(!) = ''              | ''                 | 'BEBL0105Z00' |'LED_1121'| 'IO'  | 'LED SMD BLUE(11-21/BHC-AP1Q2B2Z/2T)'                                 | ''             | ''          | ''   | '20111207'
 'LED  GREEN'               | 'SMLF'    | '15-21/GHC-YR1S1/2T'        | 'IC'     | 'BEGR0191Z00'(!) = ''              | ''                 | 'BEGR0191Z00' |'LED2S_15-21Y2C-AP1Q2B2T'| 'IC'  | 'LED SMD(2P) GREEN(15-21/GHC-YR1S1/2T)'                               | ''             | ''          | ''   | '20170503'
 'LED  GREEN'               | 'SMLF'    | '15-21/GHC-YR1S1/2T'        | 'EMPTY'  | 'BEGR0191Z00'(!) = ''              | ''                 | 'BEGR0191Z00' |'LED2S_15-21Y2C-AP1Q2B2T'| 'IO'  | 'LED SMD(2P) GREEN(15-21/GHC-YR1S1/2T)'                               | ''             | ''          | ''   | '20170503'
 'LED BLUE'                 | 'SMLF'    | '15-21/BHC-AN1P2/2T'        | 'IC'     | 'BEBL0079Z00'(!) = ''              | ''                 | 'BEBL0079Z00' |'LED2S_15-21Y2C-AP1Q2B2T'| 'IC'  | 'LED SMD(2P) BLUE 15-21/BHC-AN1P2/2T'                                 | ''             | ''          | ''   | '20170503'
 'LED BLUE'                 | 'SMLF'    | '15-21/BHC-AN1P2/2T'        | 'EMPTY'  | 'BEBL0079Z00'(!) = ''              | ''                 | 'BEBL0079Z00' |'LED2S_15-21Y2C-AP1Q2B2T'| 'IO'  | 'LED SMD(2P) BLUE 15-21/BHC-AN1P2/2T'                                 | ''             | ''          | ''   | '20170503'
 'LED_YELLOW'               | 'SMLF'    | '15-21/Y2C-AP1Q2B/2T'       | 'IC'     | 'BEYL0089Z00'(!) = ''              | ''                 | 'BEYL0089Z00' |'LED2S_15-21Y2C-AP1Q2B2T'| 'IC'  | 'LED SMD(2P)YELLOW_15-21/Y2C-AP1Q2B/2T'                               | ''             | ''          | ''   | '20170503'
 'LED_YELLOW'               | 'SMLF'    | '15-21/Y2C-AP1Q2B/2T'       | 'EMPTY'  | 'BEYL0089Z00'(!) = ''              | ''                 | 'BEYL0089Z00' |'LED2S_15-21Y2C-AP1Q2B2T'| 'IO'  | 'LED SMD(2P)YELLOW_15-21/Y2C-AP1Q2B/2T'                               | ''             | ''          | ''   | '20170503'
 'LED RED'                  | 'THLF'    | 'L-7104EW/1ID'              | 'IC'     | 'BERD0101D00'(!) = 'End of Design' | 'P/N Release'      | 'BERD0101D00' |'LED_710A8EW'| 'IC'  | 'LED DIP(2P) RED(L-7104EW/1ID)'                                       | ''             | ''          | ''   | '20120423'
 'LED RED'                  | 'THLF'    | 'L-7104EW/1ID'              | 'EMPTY'  | 'BERD0101D00'(!) = 'End of Design' | 'P/N Release'      | 'BERD0101D00' |'LED_710A8EW'| 'IO'  | 'LED DIP(2P) RED(L-7104EW/1ID)'                                       | ''             | ''          | ''   | '20120423'
 'LED GREEN'                | 'THLF'    | 'L-1384AD/1GD-3'            | 'IC'     | 'BEGR0070D00'(!) = 'End of Design' | 'End of Life'      | 'BEGR0070D00' |'LED_L1384AD_EOL'| 'IC'  | 'LED DIP(2P) GREEN L-1384AD/1GD-3'                                    | ''             | ''          | ''   | '20121127'
 'LED GREEN'                | 'THLF'    | 'L-1384AD/1GD-3'            | 'EMPTY'  | 'BEGR0070D00'(!) = 'End of Design' | 'End of Life'      | 'BEGR0070D00' |'LED_L1384AD_EOL'| 'IO'  | 'LED DIP(2P) GREEN L-1384AD/1GD-3'                                    | ''             | ''          | ''   | '20121127'
 'LED PURE ORANGE'          | 'THLF'    | 'L-1384AD/1ND'              | 'IC'     | 'BE0R0038D01'(!) = 'End of Design' | 'End of Life'      | 'BE0R0038D01' |'LED_L1384AD_EOL'| 'IC'  | 'LED DIP(2PIN) PURE ORANGE L-1384AD/1ND'                              | ''             | ''          | ''   | '20121127'
 'LED PURE ORANGE'          | 'THLF'    | 'L-1384AD/1ND'              | 'EMPTY'  | 'BE0R0038D01'(!) = 'End of Design' | 'End of Life'      | 'BE0R0038D01' |'LED_L1384AD_EOL'| 'IO'  | 'LED DIP(2PIN) PURE ORANGE L-1384AD/1ND'                              | ''             | ''          | ''   | '20121127'
 'LED ORANGE'               | 'SMLF'    | 'APDA3020-CN24A'            | 'IC'     | 'BE0R0074Z00'(!) = 'End of Design' | 'Comp-Approve'     | 'BE0R0074Z00' |'LED2S_APDA3020'| 'IC'  | 'LED SMD(4P) ORANGE(APDA3020-CN24A)'                                  | ''             | ''          | ''   | '20121201'
 'LED ORANGE'               | 'SMLF'    | 'APDA3020-CN24A'            | 'EMPTY'  | 'BE0R0074Z00'(!) = 'End of Design' | 'Comp-Approve'     | 'BE0R0074Z00' |'LED2S_APDA3020'| 'IO'  | 'LED SMD(4P) ORANGE(APDA3020-CN24A)'                                  | ''             | ''          | ''   | '20121201'
 'LED GREEN'                | 'SMLF'    | 'APDA3020-CN26A'            | 'IC'     | 'BEGR0216Z00'(!) = 'End of Design' | 'Comp-Approve'     | 'BEGR0216Z00' |'LED2S_APDA3020'| 'IC'  | 'LED SMD(4P) GREEN(APDA3020-CN26A)'                                   | ''             | ''          | ''   | '20121201'
 'LED GREEN'                | 'SMLF'    | 'APDA3020-CN26A'            | 'EMPTY'  | 'BEGR0216Z00'(!) = 'End of Design' | 'Comp-Approve'     | 'BEGR0216Z00' |'LED2S_APDA3020'| 'IO'  | 'LED SMD(4P) GREEN(APDA3020-CN26A)'                                   | ''             | ''          | ''   | '20121201'
 'LED GREEN'                | 'SMLF'    | '15-21VGC/TR8(HT)'          | 'IC'     | 'BEGR0034Z13'(!) = ''              | 'End of Life'      | 'BEGR0034Z13' |'LED_1521_ERROR_EOL'| 'IC'  | 'LED(2P.SMD) GREEN 15-21VGC/TR8(HT)-Need new spec check-20170503'     | ''             | ''          | ''   | '20130205'
 'LED GREEN'                | 'SMLF'    | '15-21VGC/TR8(HT)'          | 'EMPTY'  | 'BEGR0034Z13'(!) = ''              | 'End of Life'      | 'BEGR0034Z13' |'LED_1521_ERROR_EOL'| 'IO'  | 'LED(2P.SMD) GREEN 15-21VGC/TR8(HT)-Need new spec check-20170503'     | ''             | ''          | ''   | '20130205'
 'LED GREEN'                | 'SMLF'    | '17-21/GHC-YR1S2/3T'        | 'IC'     | 'BEGR0190Z00'(!) = ''              | ''                 | 'BEGR0190Z00' |'LED_1721'| 'IC'  | 'LED SMD(2P) GREEN(17-21/GHC-YR1S2/3T)'                               | ''             | ''          | ''   | '20130311'
 'LED GREEN'                | 'SMLF'    | '17-21/GHC-YR1S2/3T'        | 'EMPTY'  | 'BEGR0190Z00'(!) = ''              | ''                 | 'BEGR0190Z00' |'LED_1721'| 'IO'  | 'LED SMD(2P) GREEN(17-21/GHC-YR1S2/3T)'                               | ''             | ''          | ''   | '20130311'
 'LED_BLUE'                 | 'SMLF'    | 'LTST-S270TBKT'             | 'IC'     | 'BEBL0050Z08'(!) = ''              | ''                 | 'BEBL0050Z08' |'LED_LTSTS270TBKT'| 'IC'  | 'LED SMD (2P) BLUE (LTST-S270TBKT)'                                   | ''             | ''          | ''   | '20130319'
 'LED_BLUE'                 | 'SMLF'    | 'LTST-S270TBKT'             | 'EMPTY'  | 'BEBL0050Z08'(!) = ''              | ''                 | 'BEBL0050Z08' |'LED_LTSTS270TBKT'| 'IO'  | 'LED SMD (2P) BLUE (LTST-S270TBKT)'                                   | ''             | ''          | ''   | '20130319'
 'LED GREEN'                | 'SMLF'    | '19-213/GHC-YR2U1/3T'       | 'IC'     | 'BEGR0320Z00'(!) = ''              | ''                 | 'BEGR0320Z00' |'LED_1921'| 'IC'  | 'LED SMD(2P) GREEN 19-213/GHC-YR2U1/3T'                               | ''             | ''          | ''   | '20130503'
 'LED GREEN'                | 'SMLF'    | '19-213/GHC-YR2U1/3T'       | 'EMPTY'  | 'BEGR0320Z00'(!) = ''              | ''                 | 'BEGR0320Z00' |'LED_1921'| 'IO'  | 'LED SMD(2P) GREEN 19-213/GHC-YR2U1/3T'                               | ''             | ''          | ''   | '20130503'
 'LED_SMD_YELLOW'           | 'SMLF'    | '19-213/Y2C-AP1Q1BZ/3T'     | 'IC'     | 'BEYL0107Z00'(!) = ''              | ''                 | 'BEYL0107Z00' |'LED_1921'| 'IC'  | 'LED SMD YELLOW (19-213/Y2C-AP1Q1BZ/3T)'                              | ''             | ''          | ''   | '20130503'
 'LED_SMD_YELLOW'           | 'SMLF'    | '19-213/Y2C-AP1Q1BZ/3T'     | 'EMPTY'  | 'BEYL0107Z00'(!) = ''              | ''                 | 'BEYL0107Z00' |'LED_1921'| 'IO'  | 'LED SMD YELLOW (19-213/Y2C-AP1Q1BZ/3T)'                              | ''             | ''          | ''   | '20130503'
 'LED GREEN'                | 'SMLF'    | 'APT2012-CN26'              | 'IC'     | 'BEGR0266Z00'(!) = 'End of Design' | 'Comp-Approve'     | 'BEGR0266Z00' |'LED_APT2012'| 'IC'  | 'LED SMD(2P)GREEN APT2012-CN26'                                       | ''             | ''          | ''   | '20130506'
 'LED GREEN'                | 'SMLF'    | 'APT2012-CN26'              | 'EMPTY'  | 'BEGR0266Z00'(!) = 'End of Design' | 'Comp-Approve'     | 'BEGR0266Z00' |'LED_APT2012'| 'IO'  | 'LED SMD(2P)GREEN APT2012-CN26'                                       | ''             | ''          | ''   | '20130506'
 'LED YELLOW'               | 'SMLF'    | 'KPTD-1608SYCK'             | 'IC'     | 'BEYL0122Z00'(!) = 'End of Design' | 'P/N Release'      | 'BEYL0122Z00' |'LED_KPTD-1608'| 'IC'  | 'LED SMD(2P)YELLOW(KPTD-1608SYCK)'                                    | ''             | ''          | ''   | '20130513'
 'LED YELLOW'               | 'SMLF'    | 'KPTD-1608SYCK'             | 'EMPTY'  | 'BEYL0122Z00'(!) = 'End of Design' | 'P/N Release'      | 'BEYL0122Z00' |'LED_KPTD-1608'| 'IO'  | 'LED SMD(2P)YELLOW(KPTD-1608SYCK)'                                    | ''             | ''          | ''   | '20130513'
 'LED GREEN'                | 'SMLF'    | 'KPTD-1608ZGC'              | 'IC'     | 'BEGR0303Z00'(!) = 'End of Design' | 'P/N Release'      | 'BEGR0303Z00' |'LED_KPTD-1608'| 'IC'  | 'LED SMD(2P)GREEN KPTD-1608ZGC'                                       | ''             | ''          | ''   | '20130518'
 'LED GREEN'                | 'SMLF'    | 'KPTD-1608ZGC'              | 'EMPTY'  | 'BEGR0303Z00'(!) = 'End of Design' | 'P/N Release'      | 'BEGR0303Z00' |'LED_KPTD-1608'| 'IO'  | 'LED SMD(2P)GREEN KPTD-1608ZGC'                                       | ''             | ''          | ''   | '20130518'
 'LED YEL/GR'               | 'SMLF'    | '19-213SYGC/S313/TR8'       | 'IC'     | 'BEYG0075ZA1'(!) = ''              | ''                 | 'BEYG0075ZA1' |'LED_1921'| 'IC'  | 'LED SMD(2P)YEL/GR 19-213SYGC/S313/TR8'                               | ''             | ''          | ''   | '20130611'
 'LED YEL/GR'               | 'SMLF'    | '19-213SYGC/S313/TR8'       | 'EMPTY'  | 'BEYG0075ZA1'(!) = ''              | ''                 | 'BEYG0075ZA1' |'LED_1921'| 'IO'  | 'LED SMD(2P)YEL/GR 19-213SYGC/S313/TR8'                               | ''             | ''          | ''   | '20130611'
 'LED BLUE'                 | 'SMLF'    | '19-217/BHC-YL2M2TY/3T'     | 'IC'     | 'BEBL0031Z11'(!) = 'End of Design' | 'End of Life'      | 'BEBL0031Z11' |'LED_19217_EOL'| 'IC'  | 'LED SMD(2P) BLUE 19-217BHCYL2M2TY3T'                                 | ''             | ''          | ''   | '20130611'
 'LED BLUE'                 | 'SMLF'    | '19-217/BHC-YL2M2TY/3T'     | 'EMPTY'  | 'BEBL0031Z11'(!) = 'End of Design' | 'End of Life'      | 'BEBL0031Z11' |'LED_19217_EOL'| 'IO'  | 'LED SMD(2P) BLUE 19-217BHCYL2M2TY3T'                                 | ''             | ''          | ''   | '20130611'
 'LED ORANGE'               | 'SMLF'    | '19-213/S2C-AP2Q2B/3T'      | 'IC'     | 'BE0R0104Z00'(!) = ''              | ''                 | 'BE0R0104Z00' |'LED_1921'| 'IC'  | 'LED SMD ORANGE(19-213/S2C-AP2Q2B/3T)'                                | ''             | ''          | ''   | '20130611'
 'LED ORANGE'               | 'SMLF'    | '19-213/S2C-AP2Q2B/3T'      | 'EMPTY'  | 'BE0R0104Z00'(!) = ''              | ''                 | 'BE0R0104Z00' |'LED_1921'| 'IO'  | 'LED SMD ORANGE(19-213/S2C-AP2Q2B/3T)'                                | ''             | ''          | ''   | '20130611'
 'LED GREEN'                | 'THLF'    | 'LTL42TG6NH213'             | 'IC'     | 'BEGR0304D00'(!) = ''              | ''                 | 'BEGR0304D00' |'LED2P_LTL42'| 'IC'  | 'LED(DIP) GREEN(LTL42TG6NH213)'                                       | ''             | ''          | ''   | '20130614'
 'LED GREEN'                | 'THLF'    | 'LTL42TG6NH213'             | 'EMPTY'  | 'BEGR0304D00'(!) = ''              | ''                 | 'BEGR0304D00' |'LED2P_LTL42'| 'IO'  | 'LED(DIP) GREEN(LTL42TG6NH213)'                                       | ''             | ''          | ''   | '20130614'
 'LED YELLOW'               | 'THLF'    | 'LTL42NKSDH213'             | 'IC'     | 'BEYL0123D00'(!) = ''              | ''                 | 'BEYL0123D00' |'LED2P_LTL42'| 'IC'  | 'LED(DIP)YELLOW(LTL42NKSDH213)'                                       | ''             | ''          | ''   | '20130614'
 'LED YELLOW'               | 'THLF'    | 'LTL42NKSDH213'             | 'EMPTY'  | 'BEYL0123D00'(!) = ''              | ''                 | 'BEYL0123D00' |'LED2P_LTL42'| 'IO'  | 'LED(DIP)YELLOW(LTL42NKSDH213)'                                       | ''             | ''          | ''   | '20130614'
 'LED_GREEN'                | 'SMLF'    | 'LTST-C190KGKT'             | 'IC'     | 'BEGR0080Z07'(!) = 'End of Design' | 'Comp-Approve'     | 'BEGR0080Z07' |'LED_1921XA'| 'IC'  | 'LED SMD (2P)GREEN LTST-C190KGKT 0603'                                | ''             | ''          | ''   | '20130925'
 'LED_GREEN'                | 'SMLF'    | 'LTST-C190KGKT'             | 'EMPTY'  | 'BEGR0080Z07'(!) = 'End of Design' | 'Comp-Approve'     | 'BEGR0080Z07' |'LED_1921XA'| 'IO'  | 'LED SMD (2P)GREEN LTST-C190KGKT 0603'                                | ''             | ''          | ''   | '20130925'
 'LED_GREEN'                | 'SMLF'    | 'LTST-C281KGKT-5A'          | 'IC'     | 'BEGR0300Z00'(!) = ''              | ''                 | 'BEGR0300Z00' |'LED2S_0402'| 'IC'  | 'LED SMD(2P) GREEN(LTST-C281KGKT-5A)'                                 | ''             | ''          | ''   | '20140109'
 'LED_GREEN'                | 'SMLF'    | 'LTST-C281KGKT-5A'          | 'EMPTY'  | 'BEGR0300Z00'(!) = ''              | ''                 | 'BEGR0300Z00' |'LED2S_0402'| 'IO'  | 'LED SMD(2P) GREEN(LTST-C281KGKT-5A)'                                 | ''             | ''          | ''   | '20140109'
 'LED_BLUE'                 | 'THLF'    | 'A214B/SUBC/S400-A6/F14-33' | 'IC'     | 'BEBL0221D00'(!) = ''              | ''                 | 'BEBL0221D00' |'LED2P_A214BSUBCS400-A6F14-33'| 'IC'  | 'LED DIP(2P)BL A214B/SUBC/S400-A6/F14-33'                             | ''             | ''          | ''   | '20140715'
 'LED_BLUE'                 | 'THLF'    | 'A214B/SUBC/S400-A6/F14-33' | 'EMPTY'  | 'BEBL0221D00'(!) = ''              | ''                 | 'BEBL0221D00' |'LED2P_A214BSUBCS400-A6F14-33'| 'IO'  | 'LED DIP(2P)BL A214B/SUBC/S400-A6/F14-33'                             | ''             | ''          | ''   | '20140715'
 'LED_BLUE'                 | 'SMLF'    | '19-117/BHC-YL2M2QY/3T'     | 'IC'     | 'BEBL0148Z00'(!) = ''              | ''                 | 'BEBL0148Z00' |'LED_1921'| 'IC'  | 'LED SMD(2P) BLUE 19-117/BHC-YL2M2QY/3T'                              | ''             | ''          | ''   | '20140729'
 'LED_BLUE'                 | 'SMLF'    | '19-117/BHC-YL2M2QY/3T'     | 'EMPTY'  | 'BEBL0148Z00'(!) = ''              | ''                 | 'BEBL0148Z00' |'LED_1921'| 'IO'  | 'LED SMD(2P) BLUE 19-117/BHC-YL2M2QY/3T'                              | ''             | ''          | ''   | '20140729'
 'LED_RED'                  | 'SMLF'    | '19-21SDRC/S530-A2/TR8'     | 'IC'     | 'BERD0115Z00'(!) = ''              | ''                 | 'BERD0115Z00' |'LED_1921XA'| 'IC'  | 'LED SMD(2P) RED 19-21SDRC/S530-A2/TR8'                               | ''             | ''          | ''   | '20140811'
 'LED_RED'                  | 'SMLF'    | '19-21SDRC/S530-A2/TR8'     | 'EMPTY'  | 'BERD0115Z00'(!) = ''              | ''                 | 'BERD0115Z00' |'LED_1921XA'| 'IO'  | 'LED SMD(2P) RED 19-21SDRC/S530-A2/TR8'                               | ''             | ''          | ''   | '20140811'
 'LED_WHITE'                | 'SMLF'    | 'LTW-S272TLA'               | 'IC'     | 'BEWH0175Z00'(!) = ''              | ''                 | 'BEWH0175Z00' |'LED2S_LTW-S272TLA'| 'IC'  | 'LED SMD(2P) WHITE(LTW-S272TLA)'                                      | ''             | ''          | ''   | '20140811'
 'LED_WHITE'                | 'SMLF'    | 'LTW-S272TLA'               | 'EMPTY'  | 'BEWH0175Z00'(!) = ''              | ''                 | 'BEWH0175Z00' |'LED2S_LTW-S272TLA'| 'IO'  | 'LED SMD(2P) WHITE(LTW-S272TLA)'                                      | ''             | ''          | ''   | '20140811'
 'LED_GREEN'                | 'SMLF'    | 'LTST-C171KGKT'             | 'IC'     | 'BEGR0248Z00'(!) = ''              | ''                 | 'BEGR0248Z00' |'LED_C171GKT'| 'IC'  | 'LED SMD 2P GREEN(LTST-C171KGKT)'                                     | ''             | ''          | ''   | '20140818'
 'LED_GREEN'                | 'SMLF'    | 'LTST-C171KGKT'             | 'EMPTY'  | 'BEGR0248Z00'(!) = ''              | ''                 | 'BEGR0248Z00' |'LED_C171GKT'| 'IO'  | 'LED SMD 2P GREEN(LTST-C171KGKT)'                                     | ''             | ''          | ''   | '20140818'
 'LED_YELLOW'               | 'SMLF'    | '27-21UYC/S530-A3/TR8'      | 'IC'     | 'BEYL0038Z01'(!) = ''              | ''                 | 'BEYL0038Z01' |'LED2S_27-21UYC'| 'IC'  | 'LED SMD(2P)YELLOW(27-21UYC/S530-A3/TR8)'                             | ''             | ''          | ''   | '20140821'
 'LED_YELLOW'               | 'SMLF'    | '27-21UYC/S530-A3/TR8'      | 'EMPTY'  | 'BEYL0038Z01'(!) = ''              | ''                 | 'BEYL0038Z01' |'LED2S_27-21UYC'| 'IO'  | 'LED SMD(2P)YELLOW(27-21UYC/S530-A3/TR8)'                             | ''             | ''          | ''   | '20140821'
 'LED_GREEN'                | 'SMLF'    | 'LTST-C190KGKT-Q'           | 'IC'     | 'BEGR0100Z08'(!) = ''              | ''                 | 'BEGR0100Z08' |'LED_1921XA'| 'IC'  | 'LED SMD(2P)GREEN LTST-C190KGKT-Q 0603'                               | ''             | ''          | ''   | '20140901'
 'LED_GREEN'                | 'SMLF'    | 'LTST-C190KGKT-Q'           | 'EMPTY'  | 'BEGR0100Z08'(!) = ''              | ''                 | 'BEGR0100Z08' |'LED_1921XA'| 'IO'  | 'LED SMD(2P)GREEN LTST-C190KGKT-Q 0603'                               | ''             | ''          | ''   | '20140901'
 'LED_BLUE'                 | 'SMLF'    | 'LTST-C170TBKT'             | 'IC'     | 'BEBL0049Z00'(!) = ''              | ''                 | 'BEBL0049Z00' |'LED_170VY_H44'| 'IC'  | 'LED SMD 2P BLUE(LTST-C170TBKT)'                                      | ''             | ''          | ''   | '20140903'
 'LED_BLUE'                 | 'SMLF'    | 'LTST-C170TBKT'             | 'EMPTY'  | 'BEBL0049Z00'(!) = ''              | ''                 | 'BEBL0049Z00' |'LED_170VY_H44'| 'IO'  | 'LED SMD 2P BLUE(LTST-C170TBKT)'                                      | ''             | ''          | ''   | '20140903'
 'LED_RED'                  | 'SMLF'    | 'LTST-C190KRKT'             | 'IC'     | 'BERD0021Z02'(!) = ''              | ''                 | 'BERD0021Z02' |'LED_1921XA'| 'IC'  | 'LED SMD (2P) RED(LTST-C190KRKT) 0603'                                | ''             | ''          | ''   | '20141020'
 'LED_RED'                  | 'SMLF'    | 'LTST-C190KRKT'             | 'EMPTY'  | 'BERD0021Z02'(!) = ''              | ''                 | 'BERD0021Z02' |'LED_1921XA'| 'IO'  | 'LED SMD (2P) RED(LTST-C190KRKT) 0603'                                | ''             | ''          | ''   | '20141020'
 'LED_ORANGE'               | 'SMLF'    | 'LTST-C190AKT'              | 'IC'     | 'BE0R0096Z00'(!) = ''              | ''                 | 'BE0R0096Z00' |'LED_1921XA'| 'IC'  | 'LED SMD(2P) ORANGE (LTST-C190AKT)'                                   | ''             | ''          | ''   | '20141023'
 'LED_ORANGE'               | 'SMLF'    | 'LTST-C190AKT'              | 'EMPTY'  | 'BE0R0096Z00'(!) = ''              | ''                 | 'BE0R0096Z00' |'LED_1921XA'| 'IO'  | 'LED SMD(2P) ORANGE (LTST-C190AKT)'                                   | ''             | ''          | ''   | '20141023'
 'LED_WHITE'                | 'SMLF'    | 'LTW-C191UC5'               | 'IC'     | 'BEWH0047Z00'(!) = ''              | ''                 | 'BEWH0047Z00' |'LED_19217_H22'| 'IC'  | 'LED SMD 2P WHITE(LTW-C191UC5)'                                       | ''             | ''          | ''   | '20150203'
 'LED_WHITE'                | 'SMLF'    | 'LTW-C191UC5'               | 'EMPTY'  | 'BEWH0047Z00'(!) = ''              | ''                 | 'BEWH0047Z00' |'LED_19217_H22'| 'IO'  | 'LED SMD 2P WHITE(LTW-C191UC5)'                                       | ''             | ''          | ''   | '20150203'
 'LED_BLUE'                 | 'SMLF'    | 'LTST-C190TBKT'             | 'IC'     | 'BEBL0019Z03'(!) = ''              | ''                 | 'BEBL0019Z03' |'LED_1921'| 'IC'  | 'LED SMD (2P) BLUE(LTST-C190TBKT)0603'                                | ''             | ''          | ''   | '20150203'
 'LED_BLUE'                 | 'SMLF'    | 'LTST-C190TBKT'             | 'EMPTY'  | 'BEBL0019Z03'(!) = ''              | ''                 | 'BEBL0019Z03' |'LED_1921'| 'IO'  | 'LED SMD (2P) BLUE(LTST-C190TBKT)0603'                                | ''             | ''          | ''   | '20150203'
 'LED_BLUE'                 | 'SMLF'    | '19-217/BHC-ZM1N2TY/3T'     | 'IC'     | 'BEBL0224Z00'(!) = ''              | ''                 | 'BEBL0224Z00' |'LED_19217'| 'IC'  | 'LED SMD(2P) BLUE 19-217/BHC-ZM1N2TY/3T'                              | ''             | ''          | ''   | '20150203'
 'LED_BLUE'                 | 'SMLF'    | '19-217/BHC-ZM1N2TY/3T'     | 'EMPTY'  | 'BEBL0224Z00'(!) = ''              | ''                 | 'BEBL0224Z00' |'LED_19217'| 'IO'  | 'LED SMD(2P) BLUE 19-217/BHC-ZM1N2TY/3T'                              | ''             | ''          | ''   | '20150203'
 'LED_RED'                  | 'SMLF'    | '19-217/R6C-P1Q2/3T'        | 'IC'     | 'BERD0034Z07'(!) = ''              | ''                 | 'BERD0034Z07' |'LED_19217'| 'IC'  | 'LED SMD(2P) RED (19-217/R6C-P1Q2/3T)'                                | ''             | ''          | ''   | '20150203'
 'LED_RED'                  | 'SMLF'    | '19-217/R6C-P1Q2/3T'        | 'EMPTY'  | 'BERD0034Z07'(!) = ''              | ''                 | 'BERD0034Z07' |'LED_19217'| 'IO'  | 'LED SMD(2P) RED (19-217/R6C-P1Q2/3T)'                                | ''             | ''          | ''   | '20150203'
 'LED_WHITE'                | 'SMLF'    | '19-117/T1D-AP2Q2QY/3T'     | 'IC'     | 'BEWH0160Z01'(!) = ''              | ''                 | 'BEWH0160Z01' |'LED_19217'| 'IC'  | 'LED SMD(2P) WHITE(19-117/T1D-AP2Q2QY/3T)'                            | ''             | ''          | ''   | '20150203'
 'LED_WHITE'                | 'SMLF'    | '19-117/T1D-AP2Q2QY/3T'     | 'EMPTY'  | 'BEWH0160Z01'(!) = ''              | ''                 | 'BEWH0160Z01' |'LED_19217'| 'IO'  | 'LED SMD(2P) WHITE(19-117/T1D-AP2Q2QY/3T)'                            | ''             | ''          | ''   | '20150203'
 'LED_RED'                  | 'SMLF'    | 'LTST-C193KRKT-SR'          | 'IC'     | 'BERD0090Z00'(!) = ''              | ''                 | 'BERD0090Z00' |'LED_19217'| 'IC'  | 'LED SMD(2P) RED(LTST-C193KRKT-SR)'                                   | ''             | ''          | ''   | '20150303'
 'LED_RED'                  | 'SMLF'    | 'LTST-C193KRKT-SR'          | 'EMPTY'  | 'BERD0090Z00'(!) = ''              | ''                 | 'BERD0090Z00' |'LED_19217'| 'IO'  | 'LED SMD(2P) RED(LTST-C193KRKT-SR)'                                   | ''             | ''          | ''   | '20150303'
 'LED_GREEN'                | 'SMLF'    | '19-213/GVC-AMNB/3T'        | 'IC'     | 'BEGR0278Z00'(!) = ''              | ''                 | 'BEGR0278Z00' |'LED_1921'| 'IC'  | 'LED SMD(2P) GREEN(19-213/GVC-AMNB/3T)'                               | ''             | ''          | ''   | '20150305'
 'LED_GREEN'                | 'SMLF'    | '19-213/GVC-AMNB/3T'        | 'EMPTY'  | 'BEGR0278Z00'(!) = ''              | ''                 | 'BEGR0278Z00' |'LED_1921'| 'IO'  | 'LED SMD(2P) GREEN(19-213/GVC-AMNB/3T)'                               | ''             | ''          | ''   | '20150305'
 'LED_WHITE'                | 'SMLF'    | 'LTW-270TLA'                | 'IC'     | 'BEWH0043Z00'(!) = ''              | ''                 | 'BEWH0043Z00' |'LED_LTSTS270TBKT'| 'IC'  | 'LED SMD(2P) WHITE(LTW-270TLA)0603'                                   | ''             | ''          | ''   | '20150414'
 'LED_WHITE'                | 'SMLF'    | 'LTW-270TLA'                | 'EMPTY'  | 'BEWH0043Z00'(!) = ''              | ''                 | 'BEWH0043Z00' |'LED_LTSTS270TBKT'| 'IO'  | 'LED SMD(2P) WHITE(LTW-270TLA)0603'                                   | ''             | ''          | ''   | '20150414'
 'LED_RED'                  | 'SMLF'    | '17-215SDRC/S530-A2/TR8'    | 'IC'     | 'BERD0044Z00'(!) = ''              | ''                 | 'BERD0044Z00' |'LED2S_17-215SDRC'| 'IC'  | 'LED SMD(2P) RED(17-215SDRC/S530-A2/TR8)'                             | ''             | ''          | ''   | '20150811'
 'LED_RED'                  | 'SMLF'    | '17-215SDRC/S530-A2/TR8'    | 'EMPTY'  | 'BERD0044Z00'(!) = ''              | ''                 | 'BERD0044Z00' |'LED2S_17-215SDRC'| 'IO'  | 'LED SMD(2P) RED(17-215SDRC/S530-A2/TR8)'                             | ''             | ''          | ''   | '20150811'
 'LED_GREEN'                | 'SMLF'    | '17-215/GVC-ALMB/3T'        | 'IC'     | 'BEGR0157Z00'(!) = ''              | ''                 | 'BEGR0157Z00' |'LED2S_17-215SDRC'| 'IC'  | 'LED SMD(2P)GREEN 17-215/GVC-ALMB/3T'                                 | ''             | ''          | ''   | '20150811'
 'LED_GREEN'                | 'SMLF'    | '17-215/GVC-ALMB/3T'        | 'EMPTY'  | 'BEGR0157Z00'(!) = ''              | ''                 | 'BEGR0157Z00' |'LED2S_17-215SDRC'| 'IO'  | 'LED SMD(2P)GREEN 17-215/GVC-ALMB/3T'                                 | ''             | ''          | ''   | '20150811'
 'LED_BLUE'                 | 'SMLF'    | '17-21/BHC-AK1L2TX/3T'      | 'IC'     | 'BEBL0218Z00'(!) = ''              | ''                 | 'BEBL0218Z00' |'LED_1721'| 'IC'  | 'LED SMD(2P) BLUE(17-21/BHC-AK1L2TX/3T)'                              | ''             | ''          | ''   | '20150811'
 'LED_BLUE'                 | 'SMLF'    | '17-21/BHC-AK1L2TX/3T'      | 'EMPTY'  | 'BEBL0218Z00'(!) = ''              | ''                 | 'BEBL0218Z00' |'LED_1721'| 'IO'  | 'LED SMD(2P) BLUE(17-21/BHC-AK1L2TX/3T)'                              | ''             | ''          | ''   | '20150811'
 'LED_BLUE'                 | 'SMLF'    | '16-213/BHC-ZM1N2QY/3T'     | 'IC'     | 'BEBL0230Z00'(!) = ''              | ''                 | 'BEBL0230Z00' |'LED2S_0402XA'| 'IC'  | 'LED SMD(2P)BLUE(16-213/BHC-ZM1N2QY/3T)'                              | ''             | ''          | ''   | '20151026'
 'LED_BLUE'                 | 'SMLF'    | '16-213/BHC-ZM1N2QY/3T'     | 'EMPTY'  | 'BEBL0230Z00'(!) = ''              | ''                 | 'BEBL0230Z00' |'LED2S_0402XA'| 'IO'  | 'LED SMD(2P)BLUE(16-213/BHC-ZM1N2QY/3T)'                              | ''             | ''          | ''   | '20151026'
 'LED_GREEN'                | 'SMLF'    | 'LTST-C193KGKT-5A'          | 'IC'     | 'BEGR0272Z00'(!) = ''              | ''                 | 'BEGR0272Z00' |'LED_19217'| 'IC'  | 'LED SMD(2P)GREEN (LTST-C193KGKT-5A)'                                 | ''             | ''          | ''   | '20160119'
 'LED_GREEN'                | 'SMLF'    | 'LTST-C193KGKT-5A'          | 'EMPTY'  | 'BEGR0272Z00'(!) = ''              | ''                 | 'BEGR0272Z00' |'LED_19217'| 'IO'  | 'LED SMD(2P)GREEN (LTST-C193KGKT-5A)'                                 | ''             | ''          | ''   | '20160119'
 'LED_GREEN'                | 'SMLF'    | 'LTST-C193KGKT-PE'          | 'IC'     | 'BEGR0003Z00'(!) = ''              | ''                 | 'BEGR0003Z00' |'LED_19217'| 'IC'  | 'LED SMD(2P)GREEN(LTST-C193KGKT-PE)'                                  | ''             | ''          | ''   | '20160202'
 'LED_GREEN'                | 'SMLF'    | 'LTST-C193KGKT-PE'          | 'EMPTY'  | 'BEGR0003Z00'(!) = ''              | ''                 | 'BEGR0003Z00' |'LED_19217'| 'IO'  | 'LED SMD(2P)GREEN(LTST-C193KGKT-PE)'                                  | ''             | ''          | ''   | '20160202'
 'LED_GREEN'                | 'THLF'    | 'LTL-42NGY8DHBP-1'          | 'IC'     | 'BEGR0001D00'(!) = ''              | ''                 | 'BEGR0001D00' |'LED2P_LTL-14CDJNHBP'| 'IC'  | 'LED DIP (2P) GREEN (LTL-42NGY8DHBP-1)'                               | ''             | ''          | ''   | '20160218'
 'LED_GREEN'                | 'THLF'    | 'LTL-42NGY8DHBP-1'          | 'EMPTY'  | 'BEGR0001D00'(!) = ''              | ''                 | 'BEGR0001D00' |'LED2P_LTL-14CDJNHBP'| 'IO'  | 'LED DIP (2P) GREEN (LTL-42NGY8DHBP-1)'                               | ''             | ''          | ''   | '20160218'
 'LED2P_LTL42NKFDH184'      | 'THLF'    | 'LTL42NKFDH184'             | 'IC'     | 'BEAB0000D00'(!) = ''              | ''                 | 'BEAB0000D00' |'LED2P_LTL42NKFDH184'| 'IC'  | 'LED DIP(2P)AMBER(LTL42NKFDH184)'                                     | ''             | ''          | ''   | '20160628'
 'LED2P_LTL42NKFDH184'      | 'THLF'    | 'LTL42NKFDH184'             | 'EMPTY'  | 'BEAB0000D00'(!) = ''              | ''                 | 'BEAB0000D00' |'LED2P_LTL42NKFDH184'| 'IO'  | 'LED DIP(2P)AMBER(LTL42NKFDH184)'                                     | ''             | ''          | ''   | '20160628'
 'LED_BLUE'                 | 'THLF'    | 'LTL42TB6NH184'             | 'IC'     | 'BEBL0216D00'(!) = ''              | ''                 | 'BEBL0216D00' |'LED2P_LTL42TB6NH184'| 'IC'  | 'LED DIP(2P)BLUE(LTL42TB6NH184)'                                      | ''             | ''          | ''   | '20160630'
 'LED_BLUE'                 | 'THLF'    | 'LTL42TB6NH184'             | 'EMPTY'  | 'BEBL0216D00'(!) = ''              | ''                 | 'BEBL0216D00' |'LED2P_LTL42TB6NH184'| 'IO'  | 'LED DIP(2P)BLUE(LTL42TB6NH184)'                                      | ''             | ''          | ''   | '20160630'
 'LED_BLUE'                 | 'SMLF'    | 'LTST-C930TBKT'             | 'IC'     | 'BEBL0009Z00'(!) = ''              | ''                 | 'BEBL0009Z00' |'LED2S_LTST-C930TBKT'| 'IC'  | 'LED SMD(2P)BLUE(LTST-C930TBKT)'                                      | ''             | ''          | ''   | '20160620'
 'LED_BLUE'                 | 'SMLF'    | 'LTST-C930TBKT'             | 'EMPTY'  | 'BEBL0009Z00'(!) = ''              | ''                 | 'BEBL0009Z00' |'LED2S_LTST-C930TBKT'| 'IO'  | 'LED SMD(2P)BLUE(LTST-C930TBKT)'                                      | ''             | ''          | ''   | '20160620'
 'LED_BLUE'                 | 'SMLF'    | '27-21/BHC-ZM2N2TY/3C'      | 'IC'     | 'BEBL0005Z00'(!) = ''              | ''                 | 'BEBL0005Z00' |'LED2S_27-21BHC-ZM2N2TY3C'| 'IC'  | 'LED SMD(2P)BLUE(27-21/BHC-ZM2N2TY/3C)'                               | ''             | ''          | ''   | '20160810'
 'LED_BLUE'                 | 'SMLF'    | '27-21/BHC-ZM2N2TY/3C'      | 'EMPTY'  | 'BEBL0005Z00'(!) = ''              | ''                 | 'BEBL0005Z00' |'LED2S_27-21BHC-ZM2N2TY3C'| 'IO'  | 'LED SMD(2P)BLUE(27-21/BHC-ZM2N2TY/3C)'                               | ''             | ''          | ''   | '20160810'
 'LED_RED'                  | 'THLF'    | 'LTL-4221NHBP'              | 'IC'     | 'BERD0002D00'(!) = ''              | ''                 | 'BERD0002D00' |'LED2P_LTL-14CDJNHBP'| 'IC'  | 'LED DIP(2P)RED(LTL-4221NHBP)'                                        | ''             | ''          | ''   | '20160831'
 'LED_RED'                  | 'THLF'    | 'LTL-4221NHBP'              | 'EMPTY'  | 'BERD0002D00'(!) = ''              | ''                 | 'BERD0002D00' |'LED2P_LTL-14CDJNHBP'| 'IO'  | 'LED DIP(2P)RED(LTL-4221NHBP)'                                        | ''             | ''          | ''   | '20160831'
 'LED_BLUE'                 | 'THLF'    | 'LTL42TB6NHBP'              | 'IC'     | 'BEBL0042D08'(!) = ''              | ''                 | 'BEBL0042D08' |'LED2P_LTL42TB6NHBP'| 'IC'  | 'LED DIP BLUE(3 LTL42TB6NHBP)'                                        | ''             | ''          | ''   | '20160912'
 'LED_BLUE'                 | 'THLF'    | 'LTL42TB6NHBP'              | 'EMPTY'  | 'BEBL0042D08'(!) = ''              | ''                 | 'BEBL0042D08' |'LED2P_LTL42TB6NHBP'| 'IO'  | 'LED DIP BLUE(3 LTL42TB6NHBP)'                                        | ''             | ''          | ''   | '20160912'
 'LED_YELLOW'               | 'SMLF'    | 'LY M67K-J1L2-26'           | 'IC'     | 'BEYL0006Z00'(!) = ''              | ''                 | 'BEYL0006Z00' |'LED2S_LYM67K-J1L2-26'| 'IC'  | 'LED SMD(2P)YELLOW(LY M67K-J1L2-26)'                                  | ''             | ''          | ''   | '20161014'
 'LED_YELLOW'               | 'SMLF'    | 'LY M67K-J1L2-26'           | 'EMPTY'  | 'BEYL0006Z00'(!) = ''              | ''                 | 'BEYL0006Z00' |'LED2S_LYM67K-J1L2-26'| 'IO'  | 'LED SMD(2P)YELLOW(LY M67K-J1L2-26)'                                  | ''             | ''          | ''   | '20161014'
 'LED_AMBER'                | 'SMLF'    | 'LTST-C190KFKT'             | 'IC'     | 'BEAB0006Z07'(!) = ''              | ''                 | 'BEAB0006Z07' |'LED_1921'| 'IC'  | 'LED SMD(2P)AMBER (LTST-C190KFKT) 0603'                               | ''             | ''          | ''   | '20161018'
 'LED_AMBER'                | 'SMLF'    | 'LTST-C190KFKT'             | 'EMPTY'  | 'BEAB0006Z07'(!) = ''              | ''                 | 'BEAB0006Z07' |'LED_1921'| 'IO'  | 'LED SMD(2P)AMBER (LTST-C190KFKT) 0603'                               | ''             | ''          | ''   | '20161018'
 'LED_ORANGE'               | 'SMLF'    | '19-213/S2C-AQ2R2B/3T'      | 'IC'     | 'BE0R0001Z00'(!) = ''              | ''                 | 'BE0R0001Z00' |'LED_1921'| 'IC'  | 'LED SMD(2P)ORANGE(19-213/S2C-AQ2R2B/3T)'                             | ''             | ''          | ''   | '20170105'
 'LED_ORANGE'               | 'SMLF'    | '19-213/S2C-AQ2R2B/3T'      | 'EMPTY'  | 'BE0R0001Z00'(!) = ''              | ''                 | 'BE0R0001Z00' |'LED_1921'| 'IO'  | 'LED SMD(2P)ORANGE(19-213/S2C-AQ2R2B/3T)'                             | ''             | ''          | ''   | '20170105'
 'LED_GREEN'                | 'SMLF'    | 'L-C170JGCT'                | 'IC'     | 'BEGR0006Z00'(!) = ''              | ''                 | 'BEGR0006Z00' |'LED2S_L-C170JGCT'| 'IC'  | 'LED SMD(2P)GREEN(L-C170JGCT)'                                        | ''             | ''          | ''   | '20170710'
 'LED_GREEN'                | 'SMLF'    | 'L-C170JGCT'                | 'EMPTY'  | 'BEGR0006Z00'(!) = ''              | ''                 | 'BEGR0006Z00' |'LED2S_L-C170JGCT'| 'IO'  | 'LED SMD(2P)GREEN(L-C170JGCT)'                                        | ''             | ''          | ''   | '20170710'
 'LED BLUE'                 | 'SMLF'    | 'LTST-C191TBKT-DE'          | 'IC'     | 'BEBL0057Z02'(!) = ''              | ''                 | 'BEBL0057Z02' |'LED_19217_H22'| 'IC'  | 'LED SMD BLUE(LTST-C191TBKT-DE)'                                      | ''             | ''          | ''   | '20170816'
 'LED BLUE'                 | 'SMLF'    | 'LTST-C191TBKT-DE'          | 'EMPTY'  | 'BEBL0057Z02'(!) = ''              | ''                 | 'BEBL0057Z02' |'LED_19217_H22'| 'IO'  | 'LED SMD BLUE(LTST-C191TBKT-DE)'                                      | ''             | ''          | ''   | '20170816'
 'LED_YEL/GRE'              | 'SMLF'    | '16-213/G6C-BM2P1B/3T'      | 'IC'     | 'BEYG0127ZA0'(!) = ''              | ''                 | 'BEYG0127ZA0' |'LED_16213XA'| 'IC'  | 'LED SMD(2P)YEL/GRE(16-213/G6C-BM2P1B/3T)'                            | ''             | ''          | ''   | '20170912'
 'LED_YEL/GRE'              | 'SMLF'    | '16-213/G6C-BM2P1B/3T'      | 'EMPTY'  | 'BEYG0127ZA0'(!) = ''              | ''                 | 'BEYG0127ZA0' |'LED_16213XA'| 'IO'  | 'LED SMD(2P)YEL/GRE(16-213/G6C-BM2P1B/3T)'                            | ''             | ''          | ''   | '20170912'
 'LED_BLUE'                 | 'SMLF'    | 'LTST-S482TBKT-5A'          | 'IC'     | 'BEBL0174Z00'(!) = ''              | ''                 | 'BEBL0174Z00' |'LED2S_LTST-S482KRKT-5A'| 'IC'  | 'LED SMD(2P) BLUE(LTST-S482TBKT-5A)'                                  | ''             | ''          | ''   | '20171019'
 'LED_BLUE'                 | 'SMLF'    | 'LTST-S482TBKT-5A'          | 'EMPTY'  | 'BEBL0174Z00'(!) = ''              | ''                 | 'BEBL0174Z00' |'LED2S_LTST-S482KRKT-5A'| 'IO'  | 'LED SMD(2P) BLUE(LTST-S482TBKT-5A)'                                  | ''             | ''          | ''   | '20171019'
 'LED_GREEN'                | 'SMLF'    | 'LTST-C170KGKT-SR'          | 'IC'     | 'BEGR0024Z00'(!) = ''              | ''                 | 'BEGR0024Z00' |'LED_170VY_H44'| 'IC'  | 'LED SMD(2P)GREEN(LTST-C170KGKT-SR)'                                  | ''             | ''          | ''   | '20171102'
 'LED_GREEN'                | 'SMLF'    | 'LTST-C170KGKT-SR'          | 'EMPTY'  | 'BEGR0024Z00'(!) = ''              | ''                 | 'BEGR0024Z00' |'LED_170VY_H44'| 'IO'  | 'LED SMD(2P)GREEN(LTST-C170KGKT-SR)'                                  | ''             | ''          | ''   | '20171102'
 'LED_RED'                  | 'SMLF'    | 'LTST-C170KRKT-5A'          | 'IC'     | 'BERD0015Z00'(!) = ''              | ''                 | 'BERD0015Z00' |'LED_170VY_H44'| 'IC'  | 'LED SMD(2P)RED(LTST-C170KRKT-5A)'                                    | ''             | ''          | ''   | '20171102'
 'LED_RED'                  | 'SMLF'    | 'LTST-C170KRKT-5A'          | 'EMPTY'  | 'BERD0015Z00'(!) = ''              | ''                 | 'BERD0015Z00' |'LED_170VY_H44'| 'IO'  | 'LED SMD(2P)RED(LTST-C170KRKT-5A)'                                    | ''             | ''          | ''   | '20171102'
 'LED_ORANGE'               | 'SMLF'    | '16-213/S2C-BM2P1VY/3T'     | 'IC'     | 'BE0R0115Z00'(!) = ''              | ''                 | 'BE0R0115Z00' |'LED2S_0402XA'| 'IC'  | 'LED SMD (2P) ORA 16-213/S2C-BM2P1VY/3T'                              | ''             | ''          | ''   | '20180129'
 'LED_ORANGE'               | 'SMLF'    | '16-213/S2C-BM2P1VY/3T'     | 'EMPTY'  | 'BE0R0115Z00'(!) = ''              | ''                 | 'BE0R0115Z00' |'LED2S_0402XA'| 'IO'  | 'LED SMD (2P) ORA 16-213/S2C-BM2P1VY/3T'                              | ''             | ''          | ''   | '20180129'
 'LED_GREEN'                | 'THLF'    | 'LTL-533-11P2T'             | 'IC'     | 'BEGR0004D00'(!) = ''              | ''                 | 'BEGR0004D00' |'LED2P_LTL102TB8WH006PT'| 'IC'  | 'LED DIP(2P)GREEN(LTL-533-11P2T)'                                     | ''             | ''          | ''   | '20180307'
 'LED_GREEN'                | 'THLF'    | 'LTL-533-11P2T'             | 'EMPTY'  | 'BEGR0004D00'(!) = ''              | ''                 | 'BEGR0004D00' |'LED2P_LTL102TB8WH006PT'| 'IO'  | 'LED DIP(2P)GREEN(LTL-533-11P2T)'                                     | ''             | ''          | ''   | '20180307'
 'LED_GREEN'                | 'SMLF'    | 'LTST-S482KFKT-SE'          | 'IC'     | 'BEGR0028Z00'(!) = ''              | 'End of Life'      | 'BEGR0028Z00' |'LED2S_LTST-S482KFKT-SE_EOL'| 'IC'  | 'LED SMD(2P)GREEN(LTST-S482KFKT-SE)'                                  | ''             | ''          | ''   | '20180411'
 'LED_GREEN'                | 'SMLF'    | 'LTST-S482KFKT-SE'          | 'EMPTY'  | 'BEGR0028Z00'(!) = ''              | 'End of Life'      | 'BEGR0028Z00' |'LED2S_LTST-S482KFKT-SE_EOL'| 'IO'  | 'LED SMD(2P)GREEN(LTST-S482KFKT-SE)'                                  | ''             | ''          | ''   | '20180411'
 'LED_BLUE'                 | 'THLF'    | 'LTL42TBN4DHBP-1'           | 'IC'     | 'BEBL0018Z00'(!) = 'End of Design' | 'Comp-Approve'     | 'BEBL0018Z00' |'LED2P_LTL-14CDJNHBP'| 'IC'  | 'LED DIP(2P)BLUE(LTL42TBN4DHBP-1)'                                    | ''             | ''          | ''   | '20180412'
 'LED_BLUE'                 | 'THLF'    | 'LTL42TBN4DHBP-1'           | 'EMPTY'  | 'BEBL0018Z00'(!) = 'End of Design' | 'Comp-Approve'     | 'BEBL0018Z00' |'LED2P_LTL-14CDJNHBP'| 'IO'  | 'LED DIP(2P)BLUE(LTL42TBN4DHBP-1)'                                    | ''             | ''          | ''   | '20180412'
 'LED_RED'                  | 'THLF'    | 'LTL-42NEW8DHBP-1'          | 'IC'     | 'BERD0014Z00'(!) = ''              | 'End of Life'      | 'BERD0014Z00' |'LED2P_LTL-14CDJNHBP_EOL'| 'IC'  | 'LED DIP(2P)RED(LTL-42NEW8DHBP-1)'                                    | ''             | ''          | ''   | '20180412'
 'LED_RED'                  | 'THLF'    | 'LTL-42NEW8DHBP-1'          | 'EMPTY'  | 'BERD0014Z00'(!) = ''              | 'End of Life'      | 'BERD0014Z00' |'LED2P_LTL-14CDJNHBP_EOL'| 'IO'  | 'LED DIP(2P)RED(LTL-42NEW8DHBP-1)'                                    | ''             | ''          | ''   | '20180412'
 'LED_ORANGE'               | 'SMLF'    | 'LTST-C171KFKT'             | 'IC'     | 'BE0R0002Z00'(!) = ''              | ''                 | 'BE0R0002Z00' |'LED_C171GKT'| 'IC'  | 'LED SMD(2P)ORANGE(LTST-C171KFKT)'                                    | ''             | ''          | ''   | '20180418'
 'LED_ORANGE'               | 'SMLF'    | 'LTST-C171KFKT'             | 'EMPTY'  | 'BE0R0002Z00'(!) = ''              | ''                 | 'BE0R0002Z00' |'LED_C171GKT'| 'IO'  | 'LED SMD(2P)ORANGE(LTST-C171KFKT)'                                    | ''             | ''          | ''   | '20180418'
 'LED BLUE'                 | 'SMLF'    | '42-21 UBC/C470/TR8'        | 'IC'     | 'BEBL0037Z01'(!) = ''              | ''                 | 'BEBL0037Z01' |'LED_4221'| 'IC'  | 'LED SMD BLUE 42-21 UBC/C470/TR8'                                     | ''             | ''          | ''   | '20180607'
 'LED BLUE'                 | 'SMLF'    | '42-21 UBC/C470/TR8'        | 'EMPTY'  | 'BEBL0037Z01'(!) = ''              | ''                 | 'BEBL0037Z01' |'LED_4221'| 'IO'  | 'LED SMD BLUE 42-21 UBC/C470/TR8'                                     | ''             | ''          | ''   | '20180607'
 'LED_BLUE'                 | 'SMLF'    | '67-21/BHC-FQ1R2F/2T'       | 'IC'     | 'BEBL0231Z00'(!) = ''              | ''                 | 'BEBL0231Z00' |'LED2S_67-21BHC-FQ1R2F2T'| 'IC'  | 'LED SMD(2P) BLUE(67-21/BHC-FQ1R2F/2T)'                               | ''             | ''          | ''   | '20180625'
 'LED_BLUE'                 | 'SMLF'    | '67-21/BHC-FQ1R2F/2T'       | 'EMPTY'  | 'BEBL0231Z00'(!) = ''              | ''                 | 'BEBL0231Z00' |'LED2S_67-21BHC-FQ1R2F2T'| 'IO'  | 'LED SMD(2P) BLUE(67-21/BHC-FQ1R2F/2T)'                               | ''             | ''          | ''   | '20180625'
 'LED_ORANGE'               | 'SMLF'    | '67-21/S2C-AQ2S1B/2T'       | 'IC'     | 'BE0R0013Z00'(!) = ''              | ''                 | 'BE0R0013Z00' |'LED2S_67-21BHC-FQ1R2F2T'| 'IC'  | 'LED SMD(2P)ORANGE(67-21/S2C-AQ2S1B/2T)'                              | ''             | ''          | ''   | '20180718'
 'LED_ORANGE'               | 'SMLF'    | '67-21/S2C-AQ2S1B/2T'       | 'EMPTY'  | 'BE0R0013Z00'(!) = ''              | ''                 | 'BE0R0013Z00' |'LED2S_67-21BHC-FQ1R2F2T'| 'IO'  | 'LED SMD(2P)ORANGE(67-21/S2C-AQ2S1B/2T)'                              | ''             | ''          | ''   | '20180718'
 'LED_YELL/GRE'             | 'SMLF'    | '27-21/G6C-AN2Q1B/3C'       | 'IC'     | 'BEYG0146ZA0'(!) = ''              | ''                 | 'BEYG0146ZA0' |'LED2S_27-21G6C-AN2Q1B3C'| 'IC'  | 'LED SMD(2P)YELL/GRE(27-21/G6C-AN2Q1B/3C'                             | ''             | ''          | ''   | '20180814'
 'LED_YELL/GRE'             | 'SMLF'    | '27-21/G6C-AN2Q1B/3C'       | 'EMPTY'  | 'BEYG0146ZA0'(!) = ''              | ''                 | 'BEYG0146ZA0' |'LED2S_27-21G6C-AN2Q1B3C'| 'IO'  | 'LED SMD(2P)YELL/GRE(27-21/G6C-AN2Q1B/3C'                             | ''             | ''          | ''   | '20180814'
 'LED_BLUE'                 | 'THLF'    | 'LTL42TB6NH184T'            | 'IC'     | 'BEBL0236D00'(!) = ''              | ''                 | 'BEBL0236D00' |'LED2P_LTL42TB6NH184T'| 'IC'  | 'LED DIP(2P)BLUE(LTL42TB6NH184T)'                                     | ''             | ''          | ''   | '20180910'
 'LED_BLUE'                 | 'THLF'    | 'LTL42TB6NH184T'            | 'EMPTY'  | 'BEBL0236D00'(!) = ''              | ''                 | 'BEBL0236D00' |'LED2P_LTL42TB6NH184T'| 'IO'  | 'LED DIP(2P)BLUE(LTL42TB6NH184T)'                                     | ''             | ''          | ''   | '20180910'
 'LED_RED'                  | 'THLF'    | 'LTL-42NEW8DH184T'          | 'IC'     | 'BERD0142Z00'(!) = ''              | ''                 | 'BERD0142Z00' |'LED2P_LTL42TB6NH184T'| 'IC'  | 'LED DIP(2P)RED(LTL-42NEW8DH184T)'                                    | ''             | ''          | ''   | '20181001'
 'LED_RED'                  | 'THLF'    | 'LTL-42NEW8DH184T'          | 'EMPTY'  | 'BERD0142Z00'(!) = ''              | ''                 | 'BERD0142Z00' |'LED2P_LTL42TB6NH184T'| 'IO'  | 'LED DIP(2P)RED(LTL-42NEW8DH184T)'                                    | ''             | ''          | ''   | '20181001'
 'LED_YELLOW'               | 'THLF'    | 'LTL-42NSV8DHBPT'           | 'IC'     | 'BEYL0003D00'(!) = ''              | ''                 | 'BEYL0003D00' |'LED2P_LTL-14CDJNHBP'| 'IC'  | 'LED DIP(2P)YELLOW(LTL-42NSV8DHBPT)'                                  | ''             | ''          | ''   | '20181116'
 'LED_YELLOW'               | 'THLF'    | 'LTL-42NSV8DHBPT'           | 'EMPTY'  | 'BEYL0003D00'(!) = ''              | ''                 | 'BEYL0003D00' |'LED2P_LTL-14CDJNHBP'| 'IO'  | 'LED DIP(2P)YELLOW(LTL-42NSV8DHBPT)'                                  | ''             | ''          | ''   | '20181116'
 'LED_ORANGE'               | 'SMLF'    | '67-21/S2C-AS1T1/2T'        | 'IC'     | 'BE0R0127Z00'(!) = ''              | ''                 | 'BE0R0127Z00' |'LED2S_67-21S2C-AS1T12T'| 'IC'  | 'LED SMD(2P)ORANGE(67-21/S2C-AS1T1/2T)'                               | ''             | ''          | ''   | '20190111'
 'LED_ORANGE'               | 'SMLF'    | '67-21/S2C-AS1T1/2T'        | 'EMPTY'  | 'BE0R0127Z00'(!) = ''              | ''                 | 'BE0R0127Z00' |'LED2S_67-21S2C-AS1T12T'| 'IO'  | 'LED SMD(2P)ORANGE(67-21/S2C-AS1T1/2T)'                               | ''             | ''          | ''   | '20190111'
 'LED2S_SIR57-21C/L388/TR8' | 'SMLF'    | 'SIR57-21C/L388/TR8'        | 'IC'     | 'BE000082ZR0'(!) = ''              | ''                 | 'BE000082ZR0' |'LED2S_SIR57-21CL388TR8'| 'IC'  | 'LED SMD(2P)INFRARED(SIR57-21C/L388/TR8)'                             | ''             | ''          | ''   | '20190111'
 'LED2S_SIR57-21C/L388/TR8' | 'SMLF'    | 'SIR57-21C/L388/TR8'        | 'EMPTY'  | 'BE000082ZR0'(!) = ''              | ''                 | 'BE000082ZR0' |'LED2S_SIR57-21CL388TR8'| 'IO'  | 'LED SMD(2P)INFRARED(SIR57-21C/L388/TR8)'                             | ''             | ''          | ''   | '20190111'
 'LED_GREEN'                | 'SMLF'    | '27-21SYGC/S530-E2/TR8'     | 'IC'     | 'BEGR0150Z05'(!) = ''              | ''                 | 'BEGR0150Z05' |'LED2S_27-21UYC'| 'IC'  | 'LED SMD(2P)GREEN(27-21SYGC/S530-E2/TR8)'                             | ''             | ''          | ''   | '20150520'
 'LED_GREEN'                | 'SMLF'    | '27-21SYGC/S530-E2/TR8'     | 'EMPTY'  | 'BEGR0150Z05'(!) = ''              | ''                 | 'BEGR0150Z05' |'LED2S_27-21UYC'| 'IO'  | 'LED SMD(2P)GREEN(27-21SYGC/S530-E2/TR8)'                             | ''             | ''          | ''   | '20150520'
 'LED_ORANGE'               | 'THLF'    | 'LTL42NKFKNNHBP-1'          | 'IC'     | 'BE0R0130D00'(!) = ''              | ''                 | 'BE0R0130D00' |'LED2P_LTL-14CDJNHBP'| 'IC'  | 'LED DIP(2P)ORANGE(LTL42NKFKNNHBP-1)'                                 | ''             | ''          | ''   | '20190131'
 'LED_ORANGE'               | 'THLF'    | 'LTL42NKFKNNHBP-1'          | 'EMPTY'  | 'BE0R0130D00'(!) = ''              | ''                 | 'BE0R0130D00' |'LED2P_LTL-14CDJNHBP'| 'IO'  | 'LED DIP(2P)ORANGE(LTL42NKFKNNHBP-1)'                                 | ''             | ''          | ''   | '20190131'
 'LED_BLUE'                 | 'THLF'    | 'LTL102TB8WH006PT'          | 'IC'     | 'BEBL0003D00'(!) = ''              | ''                 | 'BEBL0003D00' |'LED2P_LTL102TB8WH006PT'| 'IC'  | 'LED DIP(2P)BLUE(LTL102TB8WH006PT)'                                   | ''             | ''          | ''   | '20180307'
 'LED_BLUE'                 | 'THLF'    | 'LTL102TB8WH006PT'          | 'EMPTY'  | 'BEBL0003D00'(!) = ''              | ''                 | 'BEBL0003D00' |'LED2P_LTL102TB8WH006PT'| 'IO'  | 'LED DIP(2P)BLUE(LTL102TB8WH006PT)'                                   | ''             | ''          | ''   | '20180307'
 'LED_BLUE'                 | 'THLF'    | 'LTL42FTBG9JH213T'          | 'IC'     | 'BEBL0186D00'(!) = ''              | ''                 | 'BEBL0186D00' |'LED2P_LTL-42FSVADH213T'| 'IC'  | 'LED DIP(2P)BLUE(LTL42FTBG9JH213T)'                                   | ''             | ''          | ''   | '20190410'
 'LED_BLUE'                 | 'THLF'    | 'LTL42FTBG9JH213T'          | 'EMPTY'  | 'BEBL0186D00'(!) = ''              | ''                 | 'BEBL0186D00' |'LED2P_LTL-42FSVADH213T'| 'IO'  | 'LED DIP(2P)BLUE(LTL42FTBG9JH213T)'                                   | ''             | ''          | ''   | '20190410'
 'LED_YELLOW'               | 'THLF'    | 'LTL-42FSVADH213T'          | 'IC'     | 'BEYL0149D00'(!) = ''              | ''                 | 'BEYL0149D00' |'LED2P_LTL-42FSVADH213T'| 'IC'  | 'LED DIP(2P)YELLOW(LTL-42FSVADH213T)'                                 | ''             | ''          | ''   | '20190410'
 'LED_YELLOW'               | 'THLF'    | 'LTL-42FSVADH213T'          | 'EMPTY'  | 'BEYL0149D00'(!) = ''              | ''                 | 'BEYL0149D00' |'LED2P_LTL-42FSVADH213T'| 'IO'  | 'LED DIP(2P)YELLOW(LTL-42FSVADH213T)'                                 | ''             | ''          | ''   | '20190410'
 'LED_YEL/GREEN'            | 'SMLF'    | 'QSME-C19Z'                 | 'IC'     | 'BEYL0135Z00'(!) = 'End of Design' | 'Comp-Approve'     | 'BEYL0135Z00' |'LED_1921'| 'IC'  | 'LED SMD(2P) YELGREEN(QSME-C19Z)'                                     | ''             | ''          | ''   | '20190606'
 'LED_YEL/GREEN'            | 'SMLF'    | 'QSME-C19Z'                 | 'EMPTY'  | 'BEYL0135Z00'(!) = 'End of Design' | 'Comp-Approve'     | 'BEYL0135Z00' |'LED_1921'| 'IO'  | 'LED SMD(2P) YELGREEN(QSME-C19Z)'                                     | ''             | ''          | ''   | '20190606'
 'LED_ORANGE'               | 'SMLF'    | 'QSML-C19Q'                 | 'IC'     | 'BE0R0126Z00'(!) = ''              | ''                 | 'BE0R0126Z00' |'LED_1921'| 'IC'  | 'LED SMD(2P) ORANGE(QSML-C19Q)'                                       | ''             | ''          | ''   | '20190606'
 'LED_ORANGE'               | 'SMLF'    | 'QSML-C19Q'                 | 'EMPTY'  | 'BE0R0126Z00'(!) = ''              | ''                 | 'BE0R0126Z00' |'LED_1921'| 'IO'  | 'LED SMD(2P) ORANGE(QSML-C19Q)'                                       | ''             | ''          | ''   | '20190606'
 'LED_BLUE'                 | 'SMLF'    | 'QSMR-C130-QRBC0'           | 'IC'     | 'BEBL0184Z00'(!) = ''              | ''                 | 'BEBL0184Z00' |'LED2S_QSMR-C130-QRBC0'| 'IC'  | 'LED SMD(2P) BLUE(QSMR-C130-QRBC0)'                                   | ''             | ''          | ''   | '20190610'
 'LED_BLUE'                 | 'SMLF'    | 'QSMR-C130-QRBC0'           | 'EMPTY'  | 'BEBL0184Z00'(!) = ''              | ''                 | 'BEBL0184Z00' |'LED2S_QSMR-C130-QRBC0'| 'IO'  | 'LED SMD(2P) BLUE(QSMR-C130-QRBC0)'                                   | ''             | ''          | ''   | '20190610'
 'LED_BLUE'                 | 'SMLF'    | 'LTST-C990TBKT'             | 'IC'     | 'BEBL0189Z00'(!) = ''              | ''                 | 'BEBL0189Z00' |'LED2S_QSMR-C130-QRBC0_H39'| 'IC'  | 'LED SMD(2P)BLUE(LTST-C990TBKT)'                                      | ''             | ''          | ''   | '20190805'
 'LED_BLUE'                 | 'SMLF'    | 'LTST-C990TBKT'             | 'EMPTY'  | 'BEBL0189Z00'(!) = ''              | ''                 | 'BEBL0189Z00' |'LED2S_QSMR-C130-QRBC0_H39'| 'IO'  | 'LED SMD(2P)BLUE(LTST-C990TBKT)'                                      | ''             | ''          | ''   | '20190805'
 'LED_ORANGE'               | 'SMLF'    | 'LTST-C990KFKT'             | 'IC'     | 'BE0R0134Z00'(!) = ''              | ''                 | 'BE0R0134Z00' |'LED2S_QSMR-C130-QRBC0_H39'| 'IC'  | 'LED SMD(2P)ORANGE(LTST-C990KFKT)'                                    | ''             | ''          | ''   | '20190805'
 'LED_ORANGE'               | 'SMLF'    | 'LTST-C990KFKT'             | 'EMPTY'  | 'BE0R0134Z00'(!) = ''              | ''                 | 'BE0R0134Z00' |'LED2S_QSMR-C130-QRBC0_H39'| 'IO'  | 'LED SMD(2P)ORANGE(LTST-C990KFKT)'                                    | ''             | ''          | ''   | '20190805'
 'LED_BLUE'                 | 'SMLF'    | 'LTST-C193TBKT-5A'          | 'IC'     | 'BEBL0182Z00'(!) = ''              | ''                 | 'BEBL0182Z00' |'LED_19217'| 'IC'  | 'LED SMD(2P) BLUE LTST-C193TBKT-5A'                                   | ''             | ''          | ''   | '20190925'
 'LED_BLUE'                 | 'SMLF'    | 'LTST-C193TBKT-5A'          | 'EMPTY'  | 'BEBL0182Z00'(!) = ''              | ''                 | 'BEBL0182Z00' |'LED_19217'| 'IO'  | 'LED SMD(2P) BLUE LTST-C193TBKT-5A'                                   | ''             | ''          | ''   | '20190925'
 'LED_GREEN'                | 'SMLF'    | 'LTST-T180TGKT'             | 'IC'     | 'BEGR0365Z00'(!) = ''              | ''                 | 'BEGR0365Z00' |'LED2S_LTST-T180TGKT'| 'IC'  | 'LED SMD(2P)GREEN(LTST-T180TGKT)'                                     | ''             | ''          | ''   | '20191001'
 'LED_GREEN'                | 'SMLF'    | 'LTST-T180TGKT'             | 'EMPTY'  | 'BEGR0365Z00'(!) = ''              | ''                 | 'BEGR0365Z00' |'LED2S_LTST-T180TGKT'| 'IO'  | 'LED SMD(2P)GREEN(LTST-T180TGKT)'                                     | ''             | ''          | ''   | '20191001'
 'LED_RED'                  | 'THLF'    | 'LTL-42NEW8DHBPT'           | 'IC'     | 'BERD0014D00'(!) = ''              | ''                 | 'BERD0014D00' |'LED2P_LTL-42NEW8DHBPT'| 'IC'  | 'LED DIP(2P)RED(LTL-42NEW8DHBPT)'                                     | ''             | ''          | ''   | '20191031'
 'LED_RED'                  | 'THLF'    | 'LTL-42NEW8DHBPT'           | 'EMPTY'  | 'BERD0014D00'(!) = ''              | ''                 | 'BERD0014D00' |'LED2P_LTL-42NEW8DHBPT'| 'IO'  | 'LED DIP(2P)RED(LTL-42NEW8DHBPT)'                                     | ''             | ''          | ''   | '20191031'
 'LED_YEL/GR'               | 'SMLF'    | '19-21SYGC/S530-E3/TR8'     | 'IC'     | 'BEYG0149ZA0'(!) = ''              | ''                 | 'BEYG0149ZA0' |'LED2S_19-21SYGC'| 'IC'  | 'LED SMD(2P)YEL/GR 19-21SYGC/S530-E3/TR8'                             | ''             | ''          | ''   | '20191211'
 'LED_YEL/GR'               | 'SMLF'    | '19-21SYGC/S530-E3/TR8'     | 'EMPTY'  | 'BEYG0149ZA0'(!) = ''              | ''                 | 'BEYG0149ZA0' |'LED2S_19-21SYGC'| 'IO'  | 'LED SMD(2P)YEL/GR 19-21SYGC/S530-E3/TR8'                             | ''             | ''          | ''   | '20191211'
 'LED_GREEN'                | 'SMLF'    | 'LTST-C193TGKT'             | 'IC'     | 'BEGR0314Z00'(!) = ''              | ''                 | 'BEGR0314Z00' |'LED_19217'| 'IC'  | 'LED SMD(2P)GREEN(LTST-C193TGKT)'                                     | ''             | ''          | ''   | '20191216'
 'LED_GREEN'                | 'SMLF'    | 'LTST-C193TGKT'             | 'EMPTY'  | 'BEGR0314Z00'(!) = ''              | ''                 | 'BEGR0314Z00' |'LED_19217'| 'IO'  | 'LED SMD(2P)GREEN(LTST-C193TGKT)'                                     | ''             | ''          | ''   | '20191216'
 'LED_BLUE'                 | 'SMLF'    | 'LTST-C281TBKT-5A'          | 'IC'     | 'BEBL0172Z00'(!) = ''              | ''                 | 'BEBL0172Z00' |'LED2S_0402'| 'IC'  | 'LED SMD(2P) BLUE(LTST-C281TBKT-5A)'                                  | ''             | ''          | ''   | '20121120'
 'LED_BLUE'                 | 'SMLF'    | 'LTST-C281TBKT-5A'          | 'EMPTY'  | 'BEBL0172Z00'(!) = ''              | ''                 | 'BEBL0172Z00' |'LED2S_0402'| 'IO'  | 'LED SMD(2P) BLUE(LTST-C281TBKT-5A)'                                  | ''             | ''          | ''   | '20121120'
 'LED_YELLOW'               | 'SMLF'    | 'LTST-C190KSKT-P'           | 'IC'     | 'BEYL0159Z00'(!) = ''              | ''                 | 'BEYL0159Z00' |'LED_1921XA'| 'IC'  | 'LED SMD(2P)YELLOW(LTST-C190KSKT-P)'                                  | ''             | ''          | ''   | '20200214'
 'LED_YELLOW'               | 'SMLF'    | 'LTST-C190KSKT-P'           | 'EMPTY'  | 'BEYL0159Z00'(!) = ''              | ''                 | 'BEYL0159Z00' |'LED_1921XA'| 'IO'  | 'LED SMD(2P)YELLOW(LTST-C190KSKT-P)'                                  | ''             | ''          | ''   | '20200214'
 'LED_BLUE'                 | 'SMLF'    | '12-215/BHC-YMNRY/3C'       | 'IC'     | 'BEBL0261Z00'(!) = ''              | ''                 | 'BEBL0261Z00' |'LED2S_12-215BHC-YMNRY3C'| 'IC'  | 'LED SMD(2P)BLUE(12-215/BHC-YMNRY/3C)'                                | ''             | ''          | ''   | '20200311'
 'LED_BLUE'                 | 'SMLF'    | '12-215/BHC-YMNRY/3C'       | 'EMPTY'  | 'BEBL0261Z00'(!) = ''              | ''                 | 'BEBL0261Z00' |'LED2S_12-215BHC-YMNRY3C'| 'IO'  | 'LED SMD(2P)BLUE(12-215/BHC-YMNRY/3C)'                                | ''             | ''          | ''   | '20200311'
 'LED_RED'                  | 'SMLF'    | 'LTST-S270KRKT'             | 'IC'     | 'BERD0061Z00'(!) = ''              | ''                 | 'BERD0061Z00' |'LED2S_LTST-S270KRKT'| 'IC'  | 'LED SMD(2P) RED(LTST-S270KRKT)'                                      | ''             | ''          | ''   | '20200316'
 'LED_RED'                  | 'SMLF'    | 'LTST-S270KRKT'             | 'EMPTY'  | 'BERD0061Z00'(!) = ''              | ''                 | 'BERD0061Z00' |'LED2S_LTST-S270KRKT'| 'IO'  | 'LED SMD(2P) RED(LTST-S270KRKT)'                                      | ''             | ''          | ''   | '20200316'
 'LED_BLUE'                 | 'SMLF'    | 'LTL-M11TB1H300Q'           | 'IC'     | 'BEBL0262Z00'(!) = ''              | ''                 | 'BEBL0262Z00' |'LED2S_LTL-M11KS1H300Q'| 'IC'  | 'LED SMD(2P)BLUE(LTL-M11TB1H300Q)'                                    | ''             | ''          | ''   | '20200407'
 'LED_BLUE'                 | 'SMLF'    | 'LTL-M11TB1H300Q'           | 'EMPTY'  | 'BEBL0262Z00'(!) = ''              | ''                 | 'BEBL0262Z00' |'LED2S_LTL-M11KS1H300Q'| 'IO'  | 'LED SMD(2P)BLUE(LTL-M11TB1H300Q)'                                    | ''             | ''          | ''   | '20200407'
 'LED_YELLOW'               | 'SMLF'    | 'LTL-M11KS1H300Q'           | 'IC'     | 'BEYL0163Z00'(!) = ''              | ''                 | 'BEYL0163Z00' |'LED2S_LTL-M11KS1H300Q'| 'IC'  | 'LED SMD(2P)YELLOW(LTL-M11KS1H300Q)'                                  | ''             | ''          | ''   | '20200408'
 'LED_YELLOW'               | 'SMLF'    | 'LTL-M11KS1H300Q'           | 'EMPTY'  | 'BEYL0163Z00'(!) = ''              | ''                 | 'BEYL0163Z00' |'LED2S_LTL-M11KS1H300Q'| 'IO'  | 'LED SMD(2P)YELLOW(LTL-M11KS1H300Q)'                                  | ''             | ''          | ''   | '20200408'
 'LED_GREEN'                | 'THLF'    | 'LTL-42FGYADH213T'          | 'IC'     | 'BEGR0380Z00'(!) = ''              | ''                 | 'BEGR0380Z00' |'LED2P_LTL-42FSVADH213T'| 'IC'  | 'LED DIP(2P)GREEN (LTL-42FGYADH213T)'                                 | ''             | ''          | ''   | '20200827'
 'LED_GREEN'                | 'THLF'    | 'LTL-42FGYADH213T'          | 'EMPTY'  | 'BEGR0380Z00'(!) = ''              | ''                 | 'BEGR0380Z00' |'LED2P_LTL-42FSVADH213T'| 'IO'  | 'LED DIP(2P)GREEN (LTL-42FGYADH213T)'                                 | ''             | ''          | ''   | '20200827'
 'LED_ORANGE'               | 'THLF'    | 'LTL-42FFEADH213T'          | 'IC'     | 'BE0R0140Z00'(!) = ''              | ''                 | 'BE0R0140Z00' |'LED2P_LTL-42FSVADH213T'| 'IC'  | 'LED DIP(2P)ORANGE(LTL-42FFEADH213T)'                                 | ''             | ''          | ''   | '20200903'
 'LED_ORANGE'               | 'THLF'    | 'LTL-42FFEADH213T'          | 'EMPTY'  | 'BE0R0140Z00'(!) = ''              | ''                 | 'BE0R0140Z00' |'LED2P_LTL-42FSVADH213T'| 'IO'  | 'LED DIP(2P)ORANGE(LTL-42FFEADH213T)'                                 | ''             | ''          | ''   | '20200903'
 'LED_RED'                  | 'THLF'    | 'LTL-42FRC5JH213T'          | 'IC'     | 'BERD0171Z00'(!) = ''              | ''                 | 'BERD0171Z00' |'LED2P_LTL-42FSVADH213T'| 'IC'  | 'LED DIP(2P)RED (LTL-42FRC5JH213T)'                                   | ''             | ''          | ''   | '20200903'
 'LED_RED'                  | 'THLF'    | 'LTL-42FRC5JH213T'          | 'EMPTY'  | 'BERD0171Z00'(!) = ''              | ''                 | 'BERD0171Z00' |'LED2P_LTL-42FSVADH213T'| 'IO'  | 'LED DIP(2P)RED (LTL-42FRC5JH213T)'                                   | ''             | ''          | ''   | '20200903'
 'LED_BLUE'                 | 'SMLF'    | 'LTL-M11TB1H310Q'           | 'IC'     | 'BEBL0267Z00'(!) = ''              | ''                 | 'BEBL0267Z00' |'LED2S_LTL-M11TB1H310Q'| 'IC'  | 'LED SMD(2P)BLUE(LTL-M11TB1H310Q)'                                    | ''             | ''          | ''   | '20200924'
 'LED_BLUE'                 | 'SMLF'    | 'LTL-M11TB1H310Q'           | 'EMPTY'  | 'BEBL0267Z00'(!) = ''              | ''                 | 'BEBL0267Z00' |'LED2S_LTL-M11TB1H310Q'| 'IO'  | 'LED SMD(2P)BLUE(LTL-M11TB1H310Q)'                                    | ''             | ''          | ''   | '20200924'
 'LED_YELLOW'               | 'SMLF'    | 'LTL-M11KS1H310Q'           | 'IC'     | 'BEYL0169Z00'(!) = ''              | ''                 | 'BEYL0169Z00' |'LED2S_LTL-M11TB1H310Q'| 'IC'  | 'LED SMD(2P)YELLOW(LTL-M11KS1H310Q)'                                  | ''             | ''          | ''   | '20200924'
 'LED_YELLOW'               | 'SMLF'    | 'LTL-M11KS1H310Q'           | 'EMPTY'  | 'BEYL0169Z00'(!) = ''              | ''                 | 'BEYL0169Z00' |'LED2S_LTL-M11TB1H310Q'| 'IO'  | 'LED SMD(2P)YELLOW(LTL-M11KS1H310Q)'                                  | ''             | ''          | ''   | '20200924'
 'LED_GREEN'                | 'SMLF'    | 'LTST-C171TGKT'             | 'IC'     | 'BEGR0381Z00'(!) = ''              | ''                 | 'BEGR0381Z00' |'LED_C171GKT'| 'IC'  | 'LED SMD(2P)GREEN(LTST-C171TGKT)'                                     | ''             | ''          | ''   | '20200928'
 'LED_GREEN'                | 'SMLF'    | 'LTST-C171TGKT'             | 'EMPTY'  | 'BEGR0381Z00'(!) = ''              | ''                 | 'BEGR0381Z00' |'LED_C171GKT'| 'IO'  | 'LED SMD(2P)GREEN(LTST-C171TGKT)'                                     | ''             | ''          | ''   | '20200928'
 'LED_BLUE'                 | 'THLF'    | 'LTL42TB6NHBPT'             | 'IC'     | 'BEBL0265D00'(!) = ''              | ''                 | 'BEBL0265D00' |'LED2P_LTL-14CDJNHBP'| 'IC'  | 'LED DIP(2P) BLUE (LTL42TB6NHBPT)'                                    | ''             | ''          | ''   | '20201013'
 'LED_BLUE'                 | 'THLF'    | 'LTL42TB6NHBPT'             | 'EMPTY'  | 'BEBL0265D00'(!) = ''              | ''                 | 'BEBL0265D00' |'LED2P_LTL-14CDJNHBP'| 'IO'  | 'LED DIP(2P) BLUE (LTL42TB6NHBPT)'                                    | ''             | ''          | ''   | '20201013'
 'LED_BLUE'                 | 'SMLF'    | 'LTST-M670UBKT'             | 'IC'     | 'BEBL0268Z00'(!) = ''              | ''                 | 'BEBL0268Z00' |'LED2S_LTST-M670UBKT'| 'IC'  | 'LED SMD(2P)BLUE(LTST-M670UBKT)'                                      | ''             | ''          | ''   | '20201023'
 'LED_BLUE'                 | 'SMLF'    | 'LTST-M670UBKT'             | 'EMPTY'  | 'BEBL0268Z00'(!) = ''              | ''                 | 'BEBL0268Z00' |'LED2S_LTST-M670UBKT'| 'IO'  | 'LED SMD(2P)BLUE(LTST-M670UBKT)'                                      | ''             | ''          | ''   | '20201023'
 'LED_GREEN'                | 'SMLF'    | '16-219A/GHC-YP2R1QY/3T'    | 'IC'     | 'BEGR0034Z00'(!) = ''              | ''                 | 'BEGR0034Z00' |'LED2S_16-219AGHC-YP2R1QY3T'| 'IC'  | 'LED SMD(2P)GREEN(16-219A/GHC-YP2R1QY/3T)'                            | ''             | ''          | ''   | '20210819'
 'LED_GREEN'                | 'SMLF'    | '16-219A/GHC-YP2R1QY/3T'    | 'EMPTY'  | 'BEGR0034Z00'(!) = ''              | ''                 | 'BEGR0034Z00' |'LED2S_16-219AGHC-YP2R1QY3T'| 'IO'  | 'LED SMD(2P)GREEN(16-219A/GHC-YP2R1QY/3T)'                            | ''             | ''          | ''   | '20210819'
 'LED_YELLOWGREEN'          | 'SMLF'    | 'LTST-C281KGKT-Q'           | 'IC'     | 'BEYL0142Z00'(!) = ''              | ''                 | 'BEYL0142Z00' |'LED2S_0402'| 'IC'  | 'LED SMD(2P)YELLOWGREEN(LTST-C281KGKT-Q)'                             | ''             | ''          | ''   | '20210819'
 'LED_YELLOWGREEN'          | 'SMLF'    | 'LTST-C281KGKT-Q'           | 'EMPTY'  | 'BEYL0142Z00'(!) = ''              | ''                 | 'BEYL0142Z00' |'LED2S_0402'| 'IO'  | 'LED SMD(2P)YELLOWGREEN(LTST-C281KGKT-Q)'                             | ''             | ''          | ''   | '20210819'
 'LED_YELLOW'               | 'SMLF'    | '12-215/Y2C-CP1Q2B/3C'      | 'IC'     | 'BEYL0178Z00'(!) = ''              | ''                 | 'BEYL0178Z00' |'LED2S_12-215BHC-YMNRY3C'| 'IC'  | 'LED SMD(2P)YELLOW (12-215/Y2C-CP1Q2B/3C)'                            | ''             | ''          | ''   | '20210924'
 'LED_YELLOW'               | 'SMLF'    | '12-215/Y2C-CP1Q2B/3C'      | 'EMPTY'  | 'BEYL0178Z00'(!) = ''              | ''                 | 'BEYL0178Z00' |'LED2S_12-215BHC-YMNRY3C'| 'IO'  | 'LED SMD(2P)YELLOW (12-215/Y2C-CP1Q2B/3C)'                            | ''             | ''          | ''   | '20210924'
 'LED_GREEN'                | 'SMLF'    | 'LTST-C193TGKT-F'           | 'IC'     | 'BEGR0392Z00'(!) = ''              | ''                 | 'BEGR0392Z00' |'LED_19217'| 'IC'  | 'LED SMD(2P)GREEN LTST-C193TGKT-F'                                    | ''             | ''          | ''   | '20211020'
 'LED_GREEN'                | 'SMLF'    | 'LTST-C193TGKT-F'           | 'EMPTY'  | 'BEGR0392Z00'(!) = ''              | ''                 | 'BEGR0392Z00' |'LED_19217'| 'IO'  | 'LED SMD(2P)GREEN LTST-C193TGKT-F'                                    | ''             | ''          | ''   | '20211020'
 'LED_RED'                  | 'SMLF'    | '16-213/R8C-AP1Q2B/3T'      | 'IC'     | 'BERD0092Z00'(!) = ''              | ''                 | 'BERD0092Z00' |'LED_16213XA'| 'IC'  | 'LED SMD(2P) RED(16-213/R8C-AP1Q2B/3T)'                               | ''             | ''          | ''   | '20211022'
 'LED_RED'                  | 'SMLF'    | '16-213/R8C-AP1Q2B/3T'      | 'EMPTY'  | 'BERD0092Z00'(!) = ''              | ''                 | 'BERD0092Z00' |'LED_16213XA'| 'IO'  | 'LED SMD(2P) RED(16-213/R8C-AP1Q2B/3T)'                               | ''             | ''          | ''   | '20211022'
 'LED_BLUE'                 | 'SMLF'    | '17-21/BHC-AN1P2/3T'        | 'IC'     | 'BEBL0051Z04'(!) = 'End of Design' | 'Comp-Approve'     | 'BEBL0051Z04' |'LED2S_17-21BHC-AP1Q23TXA'| 'IC'  | 'LED SMD(2P) BLUE(BHC-AN1P2/3T)'                                      | ''             | ''          | ''   | '20211209'
 'LED_BLUE'                 | 'SMLF'    | '17-21/BHC-AN1P2/3T'        | 'EMPTY'  | 'BEBL0051Z04'(!) = 'End of Design' | 'Comp-Approve'     | 'BEBL0051Z04' |'LED2S_17-21BHC-AP1Q23TXA'| 'IO'  | 'LED SMD(2P) BLUE(BHC-AN1P2/3T)'                                      | ''             | ''          | ''   | '20211209'
 'LED_YELLOW'               | 'THLF'    | 'LTL-R42FSFADH213T'         | 'IC'     | 'BEYL0182D00'(!) = ''              | ''                 | 'BEYL0182D00' |'LED2P_LTL-R42FSFADH213T'| 'IC'  | 'LED DIP(2P)YELLOW(LTL-R42FSFADH213T)'                                | ''             | ''          | ''   | '20220830'
 'LED_YELLOW'               | 'THLF'    | 'LTL-R42FSFADH213T'         | 'EMPTY'  | 'BEYL0182D00'(!) = ''              | ''                 | 'BEYL0182D00' |'LED2P_LTL-R42FSFADH213T'| 'IO'  | 'LED DIP(2P)YELLOW(LTL-R42FSFADH213T)'                                | ''             | ''          | ''   | '20220830'
 'LED_ORANGE'               | 'THLF'    | 'LTL-42FKFDH184T'           | 'IC'     | 'BE0R0143D00'(!) = ''              | ''                 | 'BE0R0143D00' |'LED2P_LTL-42FKFDH184T'| 'IC'  | 'LED DIP(2P)ORANGE(LTL-42FKFDH184T)'                                  | ''             | ''          | ''   | '20220207'
 'LED_ORANGE'               | 'THLF'    | 'LTL-42FKFDH184T'           | 'EMPTY'  | 'BE0R0143D00'(!) = ''              | ''                 | 'BE0R0143D00' |'LED2P_LTL-42FKFDH184T'| 'IO'  | 'LED DIP(2P)ORANGE(LTL-42FKFDH184T)'                                  | ''             | ''          | ''   | '20220207'
 'LED_GREEN'                | 'SMLF'    | 'LTST-C990KGKT-DT'          | 'IC'     | 'BEGR0378Z00'(!) = ''              | ''                 | 'BEGR0378Z00' |'LED2S_QSMR-C130-QRBC0_H39'| 'IC'  | 'LED SMD(2P) GREEN (LTST-C990KGKT-DT)'                                | ''             | ''          | ''   | '20220301'
 'LED_GREEN'                | 'SMLF'    | 'LTST-C990KGKT-DT'          | 'EMPTY'  | 'BEGR0378Z00'(!) = ''              | ''                 | 'BEGR0378Z00' |'LED2S_QSMR-C130-QRBC0_H39'| 'IO'  | 'LED SMD(2P) GREEN (LTST-C990KGKT-DT)'                                | ''             | ''          | ''   | '20220301'
 'LED_RED'                  | 'THLF'    | 'LTL-42FEWADHBPT'           | 'IC'     | 'BERD0183Z00'(!) = ''              | ''                 | 'BERD0183Z00' |'LED2P_LTL-42NEW8DHBPT'| 'IC'  | 'LED DIP(2P)RED (LTL-42FEWADHBPT'                                     | ''             | ''          | ''   | '20220302'
 'LED_RED'                  | 'THLF'    | 'LTL-42FEWADHBPT'           | 'EMPTY'  | 'BERD0183Z00'(!) = ''              | ''                 | 'BERD0183Z00' |'LED2P_LTL-42NEW8DHBPT'| 'IO'  | 'LED DIP(2P)RED (LTL-42FEWADHBPT'                                     | ''             | ''          | ''   | '20220302'
 'LED_BLUE'                 | 'THLF'    | 'LTLR42FTBGAJH213T'         | 'IC'     | 'BEBL0274D00'(!) = ''              | ''                 | 'BEBL0274D00' |'LED2P_LTL-42FSVADH213T'| 'IC'  | 'LED DIP(2P)BLUE (LTLR42FTBGAJH213T)'                                 | ''             | ''          | ''   | '20220304'
 'LED_BLUE'                 | 'THLF'    | 'LTLR42FTBGAJH213T'         | 'EMPTY'  | 'BEBL0274D00'(!) = ''              | ''                 | 'BEBL0274D00' |'LED2P_LTL-42FSVADH213T'| 'IO'  | 'LED DIP(2P)BLUE (LTLR42FTBGAJH213T)'                                 | ''             | ''          | ''   | '20220304'
 'LED2S_SIR57-21C/L294/TR8' | 'SMLF'    | 'SIR57-21C/L294/TR8'        | 'IC'     | 'BE000086ZR0'(!) = ''              | ''                 | 'BE000086ZR0' |'LED2S_SIR57-21CL388TR8_H160'| 'IC'  | 'LED SMD(2P)INFRARED(SIR57-21C/L294/TR8)'                             | ''             | ''          | ''   | '20220414'
 'LED2S_SIR57-21C/L294/TR8' | 'SMLF'    | 'SIR57-21C/L294/TR8'        | 'EMPTY'  | 'BE000086ZR0'(!) = ''              | ''                 | 'BE000086ZR0' |'LED2S_SIR57-21CL388TR8_H160'| 'IO'  | 'LED SMD(2P)INFRARED(SIR57-21C/L294/TR8)'                             | ''             | ''          | ''   | '20220414'
 'LED_RED'                  | 'SMLF'    | 'LTST-C191KRKT'             | 'IC'     | 'BERD0065Z00'(!) = ''              | ''                 | 'BERD0065Z00' |'LED_19217_H22'| 'IC'  | 'LED SMD(2P) RED (LTST-C191KRKT)'                                     | ''             | ''          | ''   | '20220816'
 'LED_RED'                  | 'SMLF'    | 'LTST-C191KRKT'             | 'EMPTY'  | 'BERD0065Z00'(!) = ''              | ''                 | 'BERD0065Z00' |'LED_19217_H22'| 'IO'  | 'LED SMD(2P) RED (LTST-C191KRKT)'                                     | ''             | ''          | ''   | '20220816'
 'LED_GREEN'                | 'SMLF'    | 'LTST-C191KGKT'             | 'IC'     | 'BEGR0331Z00'(!) = ''              | ''                 | 'BEGR0331Z00' |'LED_19217_H22'| 'IC'  | 'LED SMD (2P) GREEN (LTST-C191KGKT)'                                  | ''             | ''          | ''   | '20220816'
 'LED_GREEN'                | 'SMLF'    | 'LTST-C191KGKT'             | 'EMPTY'  | 'BEGR0331Z00'(!) = ''              | ''                 | 'BEGR0331Z00' |'LED_19217_H22'| 'IO'  | 'LED SMD (2P) GREEN (LTST-C191KGKT)'                                  | ''             | ''          | ''   | '20220816'
 'LED_BLUE'                 | 'THLF'    | 'HV-312470/260/SUBD-TR1'    | 'IC'     | 'BEBL0277D00'(!) = ''              | ''                 | 'BEBL0277D00' |'LED2P_HV-312470260'| 'IC'  | 'LED DIP(2P)BLUE(HV-312470/260/SUBD-TR1)'                             | ''             | ''          | ''   | '20220818'
 'LED_BLUE'                 | 'THLF'    | 'HV-312470/260/SUBD-TR1'    | 'EMPTY'  | 'BEBL0277D00'(!) = ''              | ''                 | 'BEBL0277D00' |'LED2P_HV-312470260'| 'IO'  | 'LED DIP(2P)BLUE(HV-312470/260/SUBD-TR1)'                             | ''             | ''          | ''   | '20220818'
 'LED_YELLOW'               | 'THLF'    | 'HV-312470/260/UY-TR1'      | 'IC'     | 'BEYL0186D00'(!) = ''              | ''                 | 'BEYL0186D00' |'LED2P_HV-312470260'| 'IC'  | 'LED DIP(2P)YELLOW(HV-312470/260/UY-TR1)'                             | ''             | ''          | ''   | '20220818'
 'LED_YELLOW'               | 'THLF'    | 'HV-312470/260/UY-TR1'      | 'EMPTY'  | 'BEYL0186D00'(!) = ''              | ''                 | 'BEYL0186D00' |'LED2P_HV-312470260'| 'IO'  | 'LED DIP(2P)YELLOW(HV-312470/260/UY-TR1)'                             | ''             | ''          | ''   | '20220818'
 'LED2S_LTE-S9511-E-QT'     | 'SMLF'    | 'LTE-S9511-E-QT'            | 'IC'     | 'BE000128ZR0'(!) = ''              | ''                 | 'BE000128ZR0' |'LED2S_LTE-S9511-E-QT_EOD'| 'IC'  | 'LED SMD(2P)INFRARED(LTE-S9511-E-QT)'                                 | ''             | ''          | ''   | '20221102'
 'LED2S_LTE-S9511-E-QT'     | 'SMLF'    | 'LTE-S9511-E-QT'            | 'EMPTY'  | 'BE000128ZR0'(!) = ''              | ''                 | 'BE000128ZR0' |'LED2S_LTE-S9511-E-QT_EOD'| 'IO'  | 'LED SMD(2P)INFRARED(LTE-S9511-E-QT)'                                 | ''             | ''          | ''   | '20221102'
 'LED_ORANGE'               | 'SMLF'    | '15-21/S2C-AQ2R2B/3T'       | 'IC'     | 'BE0R0149Z00'(!) = ''              | ''                 | 'BE0R0149Z00' |'LED2S_15-21S2C-AQ2R2B3T'| 'IC'  | 'LED SMD(2P)ORANGE(15-21/S2C-AQ2R2B/3T)'                              | ''             | ''          | ''   | '20230222'
 'LED_ORANGE'               | 'SMLF'    | '15-21/S2C-AQ2R2B/3T'       | 'EMPTY'  | 'BE0R0149Z00'(!) = ''              | ''                 | 'BE0R0149Z00' |'LED2S_15-21S2C-AQ2R2B3T'| 'IO'  | 'LED SMD(2P)ORANGE(15-21/S2C-AQ2R2B/3T)'                              | ''             | ''          | ''   | '20230222'
 'LED_ORANGE'               | 'SMLF'    | 'LTST-S482KFKT-SE'          | 'IC'     | 'BE0R0008Z00'(!) = ''              | ''                 | 'BE0R0008Z00' |'LED2S_LTST-S482KFKT-SE'| 'IC'  | 'LED SMD(2P)ORANGE(LTST-S482KFKT-SE)'                                 | ''             | ''          | ''   | '20230303'
 'LED_ORANGE'               | 'SMLF'    | 'LTST-S482KFKT-SE'          | 'EMPTY'  | 'BE0R0008Z00'(!) = ''              | ''                 | 'BE0R0008Z00' |'LED2S_LTST-S482KFKT-SE'| 'IO'  | 'LED SMD(2P)ORANGE(LTST-S482KFKT-SE)'                                 | ''             | ''          | ''   | '20230303'
 'LED_ORANGE'               | 'SMLF'    | 'LTST-S482KFKT-Q'           | 'IC'     | 'BE0R0155Z00'(!) = ''              | ''               | 'BE0R0155Z00' |'LED2S_LTST-S482KFKT-Q'| 'IC'  | 'LED SMD(2P) ORANGE LTST-S482KFKT-Q'                                  | ''             | ''          | ''   | '20230327'
 'LED_ORANGE'               | 'SMLF'    | 'LTST-S482KFKT-Q'           | 'EMPTY'  | 'BE0R0155Z00'(!) = ''              | ''               | 'BE0R0155Z00' |'LED2S_LTST-S482KFKT-Q'| 'IO'  | 'LED SMD(2P) ORANGE LTST-S482KFKT-Q'                                  | ''             | ''          | ''   | '20230327'

END_PART

END.

